FILE_TYPE=LIBRARY_PARTS;
primitive 'AST2600A3GP';
  pin
    'MVREF_T5':
      PIN_NUMBER='(T5,0,0,0,0,0)';
      PINUSE='POWER';
      NO_LOAD_CHECK='Both';
      NO_IO_CHECK='Both';
      NO_ASSERT_CHECK='TRUE';
      NO_DIR_CHECK='TRUE';
      ALLOW_CONNECT='TRUE';
    'MIOZ':
      PIN_NUMBER='(P5,0,0,0,0,0)';
      BIDIRECTIONAL='TRUE';
      INPUT_LOAD='(-0.01,0.01)';
      OUTPUT_LOAD='(1.0,-1.0)';
    'MRESET#':
      PIN_NUMBER='(L3,0,0,0,0,0)';
      OUTPUT_LOAD='(1.0,-1.0)';
    'MALERT#':
      PIN_NUMBER='(N4,0,0,0,0,0)';
      BIDIRECTIONAL='TRUE';
      INPUT_LOAD='(-0.01,0.01)';
      OUTPUT_LOAD='(1.0,-1.0)';
    'MDQ0':
      PIN_NUMBER='(T3,0,0,0,0,0)';
      BIDIRECTIONAL='TRUE';
      INPUT_LOAD='(-0.01,0.01)';
      OUTPUT_LOAD='(1.0,-1.0)';
    'MDQ1':
      PIN_NUMBER='(R4,0,0,0,0,0)';
      BIDIRECTIONAL='TRUE';
      INPUT_LOAD='(-0.01,0.01)';
      OUTPUT_LOAD='(1.0,-1.0)';
    'MDQ2':
      PIN_NUMBER='(U1,0,0,0,0,0)';
      BIDIRECTIONAL='TRUE';
      INPUT_LOAD='(-0.01,0.01)';
      OUTPUT_LOAD='(1.0,-1.0)';
    'MDQ3':
      PIN_NUMBER='(R3,0,0,0,0,0)';
      BIDIRECTIONAL='TRUE';
      INPUT_LOAD='(-0.01,0.01)';
      OUTPUT_LOAD='(1.0,-1.0)';
    'MDQ4':
      PIN_NUMBER='(R1,0,0,0,0,0)';
      BIDIRECTIONAL='TRUE';
      INPUT_LOAD='(-0.01,0.01)';
      OUTPUT_LOAD='(1.0,-1.0)';
    'MDQ5':
      PIN_NUMBER='(P1,0,0,0,0,0)';
      BIDIRECTIONAL='TRUE';
      INPUT_LOAD='(-0.01,0.01)';
      OUTPUT_LOAD='(1.0,-1.0)';
    'MDQ6':
      PIN_NUMBER='(P2,0,0,0,0,0)';
      BIDIRECTIONAL='TRUE';
      INPUT_LOAD='(-0.01,0.01)';
      OUTPUT_LOAD='(1.0,-1.0)';
    'MDQ7':
      PIN_NUMBER='(P3,0,0,0,0,0)';
      BIDIRECTIONAL='TRUE';
      INPUT_LOAD='(-0.01,0.01)';
      OUTPUT_LOAD='(1.0,-1.0)';
    'MDQ8':
      PIN_NUMBER='(W2,0,0,0,0,0)';
      BIDIRECTIONAL='TRUE';
      INPUT_LOAD='(-0.01,0.01)';
      OUTPUT_LOAD='(1.0,-1.0)';
    'MDQ9':
      PIN_NUMBER='(V3,0,0,0,0,0)';
      BIDIRECTIONAL='TRUE';
      INPUT_LOAD='(-0.01,0.01)';
      OUTPUT_LOAD='(1.0,-1.0)';
    'MDQ10':
      PIN_NUMBER='(W1,0,0,0,0,0)';
      BIDIRECTIONAL='TRUE';
      INPUT_LOAD='(-0.01,0.01)';
      OUTPUT_LOAD='(1.0,-1.0)';
    'MDQ11':
      PIN_NUMBER='(W3,0,0,0,0,0)';
      BIDIRECTIONAL='TRUE';
      INPUT_LOAD='(-0.01,0.01)';
      OUTPUT_LOAD='(1.0,-1.0)';
    'MDQ12':
      PIN_NUMBER='(W4,0,0,0,0,0)';
      BIDIRECTIONAL='TRUE';
      INPUT_LOAD='(-0.01,0.01)';
      OUTPUT_LOAD='(1.0,-1.0)';
    'MDQ13':
      PIN_NUMBER='(U4,0,0,0,0,0)';
      BIDIRECTIONAL='TRUE';
      INPUT_LOAD='(-0.01,0.01)';
      OUTPUT_LOAD='(1.0,-1.0)';
    'MDQ14':
      PIN_NUMBER='(V4,0,0,0,0,0)';
      BIDIRECTIONAL='TRUE';
      INPUT_LOAD='(-0.01,0.01)';
      OUTPUT_LOAD='(1.0,-1.0)';
    'MDQ15':
      PIN_NUMBER='(U3,0,0,0,0,0)';
      BIDIRECTIONAL='TRUE';
      INPUT_LOAD='(-0.01,0.01)';
      OUTPUT_LOAD='(1.0,-1.0)';
    'MDQS0':
      PIN_NUMBER='(T2,0,0,0,0,0)';
      BIDIRECTIONAL='TRUE';
      INPUT_LOAD='(-0.01,0.01)';
      OUTPUT_LOAD='(1.0,-1.0)';
    'MDQS1':
      PIN_NUMBER='(V2,0,0,0,0,0)';
      BIDIRECTIONAL='TRUE';
      INPUT_LOAD='(-0.01,0.01)';
      OUTPUT_LOAD='(1.0,-1.0)';
    'MDQS0#':
      PIN_NUMBER='(T1,0,0,0,0,0)';
      BIDIRECTIONAL='TRUE';
      INPUT_LOAD='(-0.01,0.01)';
      OUTPUT_LOAD='(1.0,-1.0)';
    'MDQS1#':
      PIN_NUMBER='(V1,0,0,0,0,0)';
      BIDIRECTIONAL='TRUE';
      INPUT_LOAD='(-0.01,0.01)';
      OUTPUT_LOAD='(1.0,-1.0)';
    'GPIOW4||LCLK||ESPICK':
      PIN_NUMBER='(AE7,0,0,0,0,0)';
      BIDIRECTIONAL='TRUE';
      INPUT_LOAD='(-0.01,0.01)';
      OUTPUT_LOAD='(1.0,-1.0)';
    'GPIOW5||LFRAME#||ESPICS#':
      PIN_NUMBER='(AF7,0,0,0,0,0)';
      BIDIRECTIONAL='TRUE';
      INPUT_LOAD='(-0.01,0.01)';
      OUTPUT_LOAD='(1.0,-1.0)';
    'GPIOW6||LSIRQ#||ESPIALT#':
      PIN_NUMBER='(AD7,0,0,0,0,0)';
      BIDIRECTIONAL='TRUE';
      INPUT_LOAD='(-0.01,0.01)';
      OUTPUT_LOAD='(1.0,-1.0)';
    'GPIOW7||LPCRST#||ESPIRST#':
      PIN_NUMBER='(AD8,0,0,0,0,0)';
      BIDIRECTIONAL='TRUE';
      INPUT_LOAD='(-0.01,0.01)';
      OUTPUT_LOAD='(1.0,-1.0)';
    'GPIOF0||SD1CLK||PWM8':
      PIN_NUMBER='(D22,0,0,0,0,0)';
      BIDIRECTIONAL='TRUE';
      INPUT_LOAD='(-0.01,0.01)';
      OUTPUT_LOAD='(1.0,-1.0)';
    'GPIOF1||SD1CMD||PWM9':
      PIN_NUMBER='(E22,0,0,0,0,0)';
      BIDIRECTIONAL='TRUE';
      INPUT_LOAD='(-0.01,0.01)';
      OUTPUT_LOAD='(1.0,-1.0)';
    'GPIOF2||SD1DAT0||PWM10':
      PIN_NUMBER='(D23,0,0,0,0,0)';
      BIDIRECTIONAL='TRUE';
      INPUT_LOAD='(-0.01,0.01)';
      OUTPUT_LOAD='(1.0,-1.0)';
    'GPIOF3||SD1DAT1||PWM11':
      PIN_NUMBER='(C23,0,0,0,0,0)';
      BIDIRECTIONAL='TRUE';
      INPUT_LOAD='(-0.01,0.01)';
      OUTPUT_LOAD='(1.0,-1.0)';
    'GPIOF4||SD1DAT2||PWM12':
      PIN_NUMBER='(C22,0,0,0,0,0)';
      BIDIRECTIONAL='TRUE';
      INPUT_LOAD='(-0.01,0.01)';
      OUTPUT_LOAD='(1.0,-1.0)';
    'GPIOF5||SD1DAT3||PWM13':
      PIN_NUMBER='(A25,0,0,0,0,0)';
      BIDIRECTIONAL='TRUE';
      INPUT_LOAD='(-0.01,0.01)';
      OUTPUT_LOAD='(1.0,-1.0)';
    'GPIOF6||SD1CD#||PWM14':
      PIN_NUMBER='(A24,0,0,0,0,0)';
      BIDIRECTIONAL='TRUE';
      INPUT_LOAD='(-0.01,0.01)';
      OUTPUT_LOAD='(1.0,-1.0)';
    'GPIOF7||SD1WP#||PWM15':
      PIN_NUMBER='(A23,0,0,0,0,0)';
      BIDIRECTIONAL='TRUE';
      INPUT_LOAD='(-0.01,0.01)';
      OUTPUT_LOAD='(1.0,-1.0)';
    'GPIOG0||TXD6||SD2CLK||SALT9':
      PIN_NUMBER='(E21,0,0,0,0,0)';
      BIDIRECTIONAL='TRUE';
      INPUT_LOAD='(-0.01,0.01)';
      OUTPUT_LOAD='(1.0,-1.0)';
    'GPIOG1||RXD6||SD2CMD||SALT10':
      PIN_NUMBER='(B22,0,0,0,0,0)';
      BIDIRECTIONAL='TRUE';
      INPUT_LOAD='(-0.01,0.01)';
      OUTPUT_LOAD='(1.0,-1.0)';
    'GPIOG2||TXD7||SD2DAT0||SALT11':
      PIN_NUMBER='(C21,0,0,0,0,0)';
      BIDIRECTIONAL='TRUE';
      INPUT_LOAD='(-0.01,0.01)';
      OUTPUT_LOAD='(1.0,-1.0)';
    'GPIOG3||RXD7||SD2DAT1||SALT12':
      PIN_NUMBER='(A22,0,0,0,0,0)';
      BIDIRECTIONAL='TRUE';
      INPUT_LOAD='(-0.01,0.01)';
      OUTPUT_LOAD='(1.0,-1.0)';
    'GPIOG4||TXD8||SD2DAT2||SALT13':
      PIN_NUMBER='(A21,0,0,0,0,0)';
      BIDIRECTIONAL='TRUE';
      INPUT_LOAD='(-0.01,0.01)';
      OUTPUT_LOAD='(1.0,-1.0)';
    'GPIOG5||RXD8||SD2DAT3||SALT14':
      PIN_NUMBER='(E20,0,0,0,0,0)';
      BIDIRECTIONAL='TRUE';
      INPUT_LOAD='(-0.01,0.01)';
      OUTPUT_LOAD='(1.0,-1.0)';
    'GPIOG6||TXD9||SD2CD#||SALT15':
      PIN_NUMBER='(D21,0,0,0,0,0)';
      BIDIRECTIONAL='TRUE';
      INPUT_LOAD='(-0.01,0.01)';
      OUTPUT_LOAD='(1.0,-1.0)';
    'GPIOG7||RXD9||SD2WP#||SALT16':
      PIN_NUMBER='(B21,0,0,0,0,0)';
      BIDIRECTIONAL='TRUE';
      INPUT_LOAD='(-0.01,0.01)';
      OUTPUT_LOAD='(1.0,-1.0)';
    'PETXP':
      PIN_NUMBER='(AE4,0,0,0,0,0)';
      OUTPUT_LOAD='(1.0,-1.0)';
    'PETXN':
      PIN_NUMBER='(AE5,0,0,0,0,0)';
      OUTPUT_LOAD='(1.0,-1.0)';
    'PERST#':
      PIN_NUMBER='(A7,0,0,0,0,0)';
      INPUT_LOAD='(-0.01,0.01)';
    'PEREFCLKP':
      PIN_NUMBER='(AD5,0,0,0,0,0)';
      INPUT_LOAD='(-0.01,0.01)';
    'PEREFCLKN':
      PIN_NUMBER='(AD6,0,0,0,0,0)';
      INPUT_LOAD='(-0.01,0.01)';
    'PERXP':
      PIN_NUMBER='(AF5,0,0,0,0,0)';
      INPUT_LOAD='(-0.01,0.01)';
    'PERXN':
      PIN_NUMBER='(AF6,0,0,0,0,0)';
      INPUT_LOAD='(-0.01,0.01)';
    'MVREF_U5':
      PIN_NUMBER='(U5,0,0,0,0,0)';
      PINUSE='POWER';
      NO_LOAD_CHECK='Both';
      NO_IO_CHECK='Both';
      NO_ASSERT_CHECK='TRUE';
      NO_DIR_CHECK='TRUE';
      ALLOW_CONNECT='TRUE';
    'MCK#':
      PIN_NUMBER='(K1,0,0,0,0,0)';
      OUTPUT_LOAD='(1.0,-1.0)';
    'MBA1':
      PIN_NUMBER='(H5,0,0,0,0,0)';
      OUTPUT_LOAD='(1.0,-1.0)';
    'MA3':
      PIN_NUMBER='(H3,0,0,0,0,0)';
      OUTPUT_LOAD='(1.0,-1.0)';
    'MA14||MACT#':
      PIN_NUMBER='(H1,0,0,0,0,0)';
      OUTPUT_LOAD='(1.0,-1.0)';
    'MBA2||MBG0':
      PIN_NUMBER='(G3,0,0,0,0,0)';
      OUTPUT_LOAD='(1.0,-1.0)';
    'GPIOJ2||HVI3C4SCL||SCL2':
      PIN_NUMBER='(E19,0,0,0,0,0)';
      BIDIRECTIONAL='TRUE';
      INPUT_LOAD='(-0.01,0.01)';
      OUTPUT_LOAD='(1.0,-1.0)';
    'MA0':
      PIN_NUMBER='(F3,0,0,0,0,0)';
      OUTPUT_LOAD='(1.0,-1.0)';
    'MA13':
      PIN_NUMBER='(K3,0,0,0,0,0)';
      OUTPUT_LOAD='(1.0,-1.0)';
    'GPIOK3||SDA6':
      PIN_NUMBER='(E13,0,0,0,0,0)';
      BIDIRECTIONAL='TRUE';
      INPUT_LOAD='(-0.01,0.01)';
      OUTPUT_LOAD='(1.0,-1.0)';
    'MBA0':
      PIN_NUMBER='(G4,0,0,0,0,0)';
      OUTPUT_LOAD='(1.0,-1.0)';
    'MA11':
      PIN_NUMBER='(G1,0,0,0,0,0)';
      OUTPUT_LOAD='(1.0,-1.0)';
    'MDM0':
      PIN_NUMBER='(N3,0,0,0,0,0)';
      OUTPUT_LOAD='(1.0,-1.0)';
    'GPIOJ7||HVI3C6SDA||SDA4':
      PIN_NUMBER='(D19,0,0,0,0,0)';
      BIDIRECTIONAL='TRUE';
      INPUT_LOAD='(-0.01,0.01)';
      OUTPUT_LOAD='(1.0,-1.0)';
    'MA6':
      PIN_NUMBER='(M5,0,0,0,0,0)';
      OUTPUT_LOAD='(1.0,-1.0)';
    'MA5':
      PIN_NUMBER='(L1,0,0,0,0,0)';
      OUTPUT_LOAD='(1.0,-1.0)';
    'MCS#':
      PIN_NUMBER='(H2,0,0,0,0,0)';
      OUTPUT_LOAD='(1.0,-1.0)';
    'MA8':
      PIN_NUMBER='(M1,0,0,0,0,0)';
      OUTPUT_LOAD='(1.0,-1.0)';
    'MA12':
      PIN_NUMBER='(L4,0,0,0,0,0)';
      OUTPUT_LOAD='(1.0,-1.0)';
    'MDM1':
      PIN_NUMBER='(R5,0,0,0,0,0)';
      OUTPUT_LOAD='(1.0,-1.0)';
    'GPIOK5||SDA7':
      PIN_NUMBER='(E11,0,0,0,0,0)';
      BIDIRECTIONAL='TRUE';
      INPUT_LOAD='(-0.01,0.01)';
      OUTPUT_LOAD='(1.0,-1.0)';
    'MA15||MBG1':
      PIN_NUMBER='(M3,0,0,0,0,0)';
      OUTPUT_LOAD='(1.0,-1.0)';
    'GPIOJ0||HVI3C3SCL||SCL1':
      PIN_NUMBER='(B20,0,0,0,0,0)';
      BIDIRECTIONAL='TRUE';
      INPUT_LOAD='(-0.01,0.01)';
      OUTPUT_LOAD='(1.0,-1.0)';
    'GPIOK6||SCL8':
      PIN_NUMBER='(F13,0,0,0,0,0)';
      BIDIRECTIONAL='TRUE';
      INPUT_LOAD='(-0.01,0.01)';
      OUTPUT_LOAD='(1.0,-1.0)';
    'MA10':
      PIN_NUMBER='(F2,0,0,0,0,0)';
      OUTPUT_LOAD='(1.0,-1.0)';
    'MRAS#':
      PIN_NUMBER='(J5,0,0,0,0,0)';
      OUTPUT_LOAD='(1.0,-1.0)';
    'MA4':
      PIN_NUMBER='(J3,0,0,0,0,0)';
      OUTPUT_LOAD='(1.0,-1.0)';
    'GPIOK4||SCL7':
      PIN_NUMBER='(D11,0,0,0,0,0)';
      BIDIRECTIONAL='TRUE';
      INPUT_LOAD='(-0.01,0.01)';
      OUTPUT_LOAD='(1.0,-1.0)';
    'MA9':
      PIN_NUMBER='(N1,0,0,0,0,0)';
      OUTPUT_LOAD='(1.0,-1.0)';
    'GPIOJ4||HVI3C5SCL||SCL3':
      PIN_NUMBER='(C19,0,0,0,0,0)';
      BIDIRECTIONAL='TRUE';
      INPUT_LOAD='(-0.01,0.01)';
      OUTPUT_LOAD='(1.0,-1.0)';
    'MA1':
      PIN_NUMBER='(K5,0,0,0,0,0)';
      OUTPUT_LOAD='(1.0,-1.0)';
    'GPIOK2||SCL6':
      PIN_NUMBER='(D12,0,0,0,0,0)';
      BIDIRECTIONAL='TRUE';
      INPUT_LOAD='(-0.01,0.01)';
      OUTPUT_LOAD='(1.0,-1.0)';
    'GPIOJ3||HVI3C4SDA||SDA2':
      PIN_NUMBER='(D20,0,0,0,0,0)';
      BIDIRECTIONAL='TRUE';
      INPUT_LOAD='(-0.01,0.01)';
      OUTPUT_LOAD='(1.0,-1.0)';
    'MCAS#':
      PIN_NUMBER='(J4,0,0,0,0,0)';
      OUTPUT_LOAD='(1.0,-1.0)';
    'GPIOW0||LAD0||ESPID0':
      PIN_NUMBER='(AB7,0,0,0,0,0)';
      BIDIRECTIONAL='TRUE';
      INPUT_LOAD='(-0.01,0.01)';
      OUTPUT_LOAD='(1.0,-1.0)';
    'MCK':
      PIN_NUMBER='(K2,0,0,0,0,0)';
      OUTPUT_LOAD='(1.0,-1.0)';
    'MA2':
      PIN_NUMBER='(F1,0,0,0,0,0)';
      OUTPUT_LOAD='(1.0,-1.0)';
    'MWE#':
      PIN_NUMBER='(G5,0,0,0,0,0)';
      OUTPUT_LOAD='(1.0,-1.0)';
    'GPIOJ6||HVI3C6SCL||SCL4':
      PIN_NUMBER='(C20,0,0,0,0,0)';
      BIDIRECTIONAL='TRUE';
      INPUT_LOAD='(-0.01,0.01)';
      OUTPUT_LOAD='(1.0,-1.0)';
    'MA7':
      PIN_NUMBER='(M2,0,0,0,0,0)';
      OUTPUT_LOAD='(1.0,-1.0)';
    'GPIOK0||SCL5':
      PIN_NUMBER='(A11,0,0,0,0,0)';
      BIDIRECTIONAL='TRUE';
      INPUT_LOAD='(-0.01,0.01)';
      OUTPUT_LOAD='(1.0,-1.0)';
    'MODT':
      PIN_NUMBER='(J1,0,0,0,0,0)';
      OUTPUT_LOAD='(1.0,-1.0)';
    'GPIOW3||LAD3||ESPID3':
      PIN_NUMBER='(AC7,0,0,0,0,0)';
      BIDIRECTIONAL='TRUE';
      INPUT_LOAD='(-0.01,0.01)';
      OUTPUT_LOAD='(1.0,-1.0)';
    'GPIOJ1||HVI3C3SDA||SDA1':
      PIN_NUMBER='(A20,0,0,0,0,0)';
      BIDIRECTIONAL='TRUE';
      INPUT_LOAD='(-0.01,0.01)';
      OUTPUT_LOAD='(1.0,-1.0)';
    'GPIOW2||LAD2||ESPID2':
      PIN_NUMBER='(AC8,0,0,0,0,0)';
      BIDIRECTIONAL='TRUE';
      INPUT_LOAD='(-0.01,0.01)';
      OUTPUT_LOAD='(1.0,-1.0)';
    'GPIOJ5||HVI3C5SDA||SDA3':
      PIN_NUMBER='(A19,0,0,0,0,0)';
      BIDIRECTIONAL='TRUE';
      INPUT_LOAD='(-0.01,0.01)';
      OUTPUT_LOAD='(1.0,-1.0)';
    'GPIOW1||LAD1||ESPID1':
      PIN_NUMBER='(AB8,0,0,0,0,0)';
      BIDIRECTIONAL='TRUE';
      INPUT_LOAD='(-0.01,0.01)';
      OUTPUT_LOAD='(1.0,-1.0)';
    'MCKE':
      PIN_NUMBER='(L5,0,0,0,0,0)';
      OUTPUT_LOAD='(1.0,-1.0)';
    'GPIOK1||SDA5':
      PIN_NUMBER='(C11,0,0,0,0,0)';
      BIDIRECTIONAL='TRUE';
      INPUT_LOAD='(-0.01,0.01)';
      OUTPUT_LOAD='(1.0,-1.0)';
    'GPIOK7||SDA8':
      PIN_NUMBER='(E12,0,0,0,0,0)';
      BIDIRECTIONAL='TRUE';
      INPUT_LOAD='(-0.01,0.01)';
      OUTPUT_LOAD='(1.0,-1.0)';
    'RCREFCLKP':
      PIN_NUMBER='(AE1,0,0,0,0,0)';
      INPUT_LOAD='(-0.01,0.01)';
    'RCREFCLKN':
      PIN_NUMBER='(AE2,0,0,0,0,0)';
      INPUT_LOAD='(-0.01,0.01)';
    'RCRXP':
      PIN_NUMBER='(AD2,0,0,0,0,0)';
      INPUT_LOAD='(-0.01,0.01)';
    'RCRXN':
      PIN_NUMBER='(AD3,0,0,0,0,0)';
      INPUT_LOAD='(-0.01,0.01)';
    'RCTXP':
      PIN_NUMBER='(AF2,0,0,0,0,0)';
      OUTPUT_LOAD='(1.0,-1.0)';
    'RCTXN':
      PIN_NUMBER='(AF3,0,0,0,0,0)';
      OUTPUT_LOAD='(1.0,-1.0)';
    'DPTXP0':
      PIN_NUMBER='(AC1,0,0,0,0,0)';
      OUTPUT_LOAD='(1.0,-1.0)';
    'DPTXN0':
      PIN_NUMBER='(AB1,0,0,0,0,0)';
      OUTPUT_LOAD='(1.0,-1.0)';
    'DPAUXP':
      PIN_NUMBER='(AC3,0,0,0,0,0)';
      BIDIRECTIONAL='TRUE';
      INPUT_LOAD='(-0.01,0.01)';
      OUTPUT_LOAD='(1.0,-1.0)';
    'DPAUXN':
      PIN_NUMBER='(AB3,0,0,0,0,0)';
      BIDIRECTIONAL='TRUE';
      INPUT_LOAD='(-0.01,0.01)';
      OUTPUT_LOAD='(1.0,-1.0)';
    'DPHPD':
      PIN_NUMBER='(C7,0,0,0,0,0)';
      INPUT_LOAD='(-0.01,0.01)';
    'DPTXP1':
      PIN_NUMBER='(AB2,0,0,0,0,0)';
      OUTPUT_LOAD='(1.0,-1.0)';
    'DPTXN1':
      PIN_NUMBER='(AA2,0,0,0,0,0)';
      OUTPUT_LOAD='(1.0,-1.0)';
    'GPIOL0||SCL9':
      PIN_NUMBER='(D15,0,0,0,0,0)';
      BIDIRECTIONAL='TRUE';
      INPUT_LOAD='(-0.01,0.01)';
      OUTPUT_LOAD='(1.0,-1.0)';
    'GPIOL1||SDA9':
      PIN_NUMBER='(A14,0,0,0,0,0)';
      BIDIRECTIONAL='TRUE';
      INPUT_LOAD='(-0.01,0.01)';
      OUTPUT_LOAD='(1.0,-1.0)';
    'GPIOL2||SCL10':
      PIN_NUMBER='(E15,0,0,0,0,0)';
      BIDIRECTIONAL='TRUE';
      INPUT_LOAD='(-0.01,0.01)';
      OUTPUT_LOAD='(1.0,-1.0)';
    'GPIOL3||SDA10':
      PIN_NUMBER='(A13,0,0,0,0,0)';
      BIDIRECTIONAL='TRUE';
      INPUT_LOAD='(-0.01,0.01)';
      OUTPUT_LOAD='(1.0,-1.0)';
    'GPIOA0||SCL11||MDC3':
      PIN_NUMBER='(M24,0,0,0,0,0)';
      BIDIRECTIONAL='TRUE';
      INPUT_LOAD='(-0.01,0.01)';
      OUTPUT_LOAD='(1.0,-1.0)';
    'GPIOA1||SDA11||MDIO3':
      PIN_NUMBER='(M25,0,0,0,0,0)';
      BIDIRECTIONAL='TRUE';
      INPUT_LOAD='(-0.01,0.01)';
      OUTPUT_LOAD='(1.0,-1.0)';
    'GPIOA2||SCL12||MDC4':
      PIN_NUMBER='(L26,0,0,0,0,0)';
      BIDIRECTIONAL='TRUE';
      INPUT_LOAD='(-0.01,0.01)';
      OUTPUT_LOAD='(1.0,-1.0)';
    'GPIOA3||SDA12||MDIO4':
      PIN_NUMBER='(K24,0,0,0,0,0)';
      BIDIRECTIONAL='TRUE';
      INPUT_LOAD='(-0.01,0.01)';
      OUTPUT_LOAD='(1.0,-1.0)';
    'GPIOA6||MAC3LINK||SCL14||SGPM2O||SGPS2I0':
      PIN_NUMBER='(L23,0,0,0,0,0)';
      BIDIRECTIONAL='TRUE';
      INPUT_LOAD='(-0.01,0.01)';
      OUTPUT_LOAD='(1.0,-1.0)';
    'GPIOA7||MAC4LINK||SDA14||SGPM2I||SGPS2I1':
      PIN_NUMBER='(K25,0,0,0,0,0)';
      BIDIRECTIONAL='TRUE';
      INPUT_LOAD='(-0.01,0.01)';
      OUTPUT_LOAD='(1.0,-1.0)';
    'GPIOA4||MAC1LINK||SCL13||SGPM2CK||SGPS2CK':
      PIN_NUMBER='(K26,0,0,0,0,0)';
      BIDIRECTIONAL='TRUE';
      INPUT_LOAD='(-0.01,0.01)';
      OUTPUT_LOAD='(1.0,-1.0)';
    'GPIOA5||MAC2LINK||SDA13||SGPM2LD||SGPS2LD':
      PIN_NUMBER='(L24,0,0,0,0,0)';
      BIDIRECTIONAL='TRUE';
      INPUT_LOAD='(-0.01,0.01)';
      OUTPUT_LOAD='(1.0,-1.0)';
    'GPIOH0||SGPM1CK':
      PIN_NUMBER='(A18,0,0,0,0,0)';
      BIDIRECTIONAL='TRUE';
      INPUT_LOAD='(-0.01,0.01)';
      OUTPUT_LOAD='(1.0,-1.0)';
    'GPIOH1||SGPM1LD':
      PIN_NUMBER='(B18,0,0,0,0,0)';
      BIDIRECTIONAL='TRUE';
      INPUT_LOAD='(-0.01,0.01)';
      OUTPUT_LOAD='(1.0,-1.0)';
    'GPIOH2||SGPM1O':
      PIN_NUMBER='(C18,0,0,0,0,0)';
      BIDIRECTIONAL='TRUE';
      INPUT_LOAD='(-0.01,0.01)';
      OUTPUT_LOAD='(1.0,-1.0)';
    'GPIOH3||SGPM1I':
      PIN_NUMBER='(A17,0,0,0,0,0)';
      BIDIRECTIONAL='TRUE';
      INPUT_LOAD='(-0.01,0.01)';
      OUTPUT_LOAD='(1.0,-1.0)';
    'GPIOH4||SGPS1CK||SCL15':
      PIN_NUMBER='(D18,0,0,0,0,0)';
      BIDIRECTIONAL='TRUE';
      INPUT_LOAD='(-0.01,0.01)';
      OUTPUT_LOAD='(1.0,-1.0)';
    'GPIOH5||SGPS1LD||SDA15':
      PIN_NUMBER='(B17,0,0,0,0,0)';
      BIDIRECTIONAL='TRUE';
      INPUT_LOAD='(-0.01,0.01)';
      OUTPUT_LOAD='(1.0,-1.0)';
    'GPIOH6||SGPS1I0||SCL16':
      PIN_NUMBER='(C17,0,0,0,0,0)';
      BIDIRECTIONAL='TRUE';
      INPUT_LOAD='(-0.01,0.01)';
      OUTPUT_LOAD='(1.0,-1.0)';
    'GPIOH7||SGPS1I1||SDA16':
      PIN_NUMBER='(E18,0,0,0,0,0)';
      BIDIRECTIONAL='TRUE';
      INPUT_LOAD='(-0.01,0.01)';
      OUTPUT_LOAD='(1.0,-1.0)';
    'GPIOS2||PEWAKE#':
      PIN_NUMBER='(T26,0,0,0,0,0)';
      BIDIRECTIONAL='TRUE';
      INPUT_LOAD='(-0.01,0.01)';
      OUTPUT_LOAD='(1.0,-1.0)';
    'GPIOS3||OSCCLK':
      PIN_NUMBER='(R24,0,0,0,0,0)';
      BIDIRECTIONAL='TRUE';
      INPUT_LOAD='(-0.01,0.01)';
      OUTPUT_LOAD='(1.0,-1.0)';
    'FWSPICS0#':
      PIN_NUMBER='(0,AB14,0,0,0,0)';
      OUTPUT_LOAD='(1.0,-1.0)';
    'GPIOM0||NCTS1':
      PIN_NUMBER='(0,D14,0,0,0,0)';
      BIDIRECTIONAL='TRUE';
      INPUT_LOAD='(-0.01,0.01)';
      OUTPUT_LOAD='(1.0,-1.0)';
    'GPIOM1||NDCD1':
      PIN_NUMBER='(0,B13,0,0,0,0)';
      BIDIRECTIONAL='TRUE';
      INPUT_LOAD='(-0.01,0.01)';
      OUTPUT_LOAD='(1.0,-1.0)';
    'GPIOM2||NDSR1':
      PIN_NUMBER='(0,A12,0,0,0,0)';
      BIDIRECTIONAL='TRUE';
      INPUT_LOAD='(-0.01,0.01)';
      OUTPUT_LOAD='(1.0,-1.0)';
    'GPIOM3||NRI1':
      PIN_NUMBER='(0,E14,0,0,0,0)';
      BIDIRECTIONAL='TRUE';
      INPUT_LOAD='(-0.01,0.01)';
      OUTPUT_LOAD='(1.0,-1.0)';
    'GPIOM4||NDTR1':
      PIN_NUMBER='(0,B12,0,0,0,0)';
      BIDIRECTIONAL='TRUE';
      INPUT_LOAD='(-0.01,0.01)';
      OUTPUT_LOAD='(1.0,-1.0)';
    'GPIOM5||NRTS1':
      PIN_NUMBER='(0,C12,0,0,0,0)';
      BIDIRECTIONAL='TRUE';
      INPUT_LOAD='(-0.01,0.01)';
      OUTPUT_LOAD='(1.0,-1.0)';
    'GPIOM6||TXD1':
      PIN_NUMBER='(0,C13,0,0,0,0)';
      BIDIRECTIONAL='TRUE';
      INPUT_LOAD='(-0.01,0.01)';
      OUTPUT_LOAD='(1.0,-1.0)';
    'GPIOM7||RXD1':
      PIN_NUMBER='(0,D13,0,0,0,0)';
      BIDIRECTIONAL='TRUE';
      INPUT_LOAD='(-0.01,0.01)';
      OUTPUT_LOAD='(1.0,-1.0)';
    'GPION0||NCTS2':
      PIN_NUMBER='(0,P25,0,0,0,0)';
      BIDIRECTIONAL='TRUE';
      INPUT_LOAD='(-0.01,0.01)';
      OUTPUT_LOAD='(1.0,-1.0)';
    'GPION1||NDCD2':
      PIN_NUMBER='(0,N23,0,0,0,0)';
      BIDIRECTIONAL='TRUE';
      INPUT_LOAD='(-0.01,0.01)';
      OUTPUT_LOAD='(1.0,-1.0)';
    'GPION2||NDSR2':
      PIN_NUMBER='(0,N25,0,0,0,0)';
      BIDIRECTIONAL='TRUE';
      INPUT_LOAD='(-0.01,0.01)';
      OUTPUT_LOAD='(1.0,-1.0)';
    'GPION3||NRI2':
      PIN_NUMBER='(0,N24,0,0,0,0)';
      BIDIRECTIONAL='TRUE';
      INPUT_LOAD='(-0.01,0.01)';
      OUTPUT_LOAD='(1.0,-1.0)';
    'GPION4||NDTR2':
      PIN_NUMBER='(0,P26,0,0,0,0)';
      BIDIRECTIONAL='TRUE';
      INPUT_LOAD='(-0.01,0.01)';
      OUTPUT_LOAD='(1.0,-1.0)';
    'GPION5||NRTS2':
      PIN_NUMBER='(0,M23,0,0,0,0)';
      BIDIRECTIONAL='TRUE';
      INPUT_LOAD='(-0.01,0.01)';
      OUTPUT_LOAD='(1.0,-1.0)';
    'GPION6||TXD2':
      PIN_NUMBER='(0,N26,0,0,0,0)';
      BIDIRECTIONAL='TRUE';
      INPUT_LOAD='(-0.01,0.01)';
      OUTPUT_LOAD='(1.0,-1.0)';
    'GPION7||RXD2':
      PIN_NUMBER='(0,M26,0,0,0,0)';
      BIDIRECTIONAL='TRUE';
      INPUT_LOAD='(-0.01,0.01)';
      OUTPUT_LOAD='(1.0,-1.0)';
    'GPIOL5||RXD3':
      PIN_NUMBER='(0,F15,0,0,0,0)';
      BIDIRECTIONAL='TRUE';
      INPUT_LOAD='(-0.01,0.01)';
      OUTPUT_LOAD='(1.0,-1.0)';
    'GPIOL4||TXD3':
      PIN_NUMBER='(0,C15,0,0,0,0)';
      BIDIRECTIONAL='TRUE';
      INPUT_LOAD='(-0.01,0.01)';
      OUTPUT_LOAD='(1.0,-1.0)';
    'FWSPICS1#':
      PIN_NUMBER='(0,AA13,0,0,0,0)';
      OUTPUT_LOAD='(1.0,-1.0)';
    'FWSPICS2#':
      PIN_NUMBER='(0,AC13,0,0,0,0)';
      OUTPUT_LOAD='(1.0,-1.0)';
    'GPIOV0||SIOS3#':
      PIN_NUMBER='(0,AB15,0,0,0,0)';
      BIDIRECTIONAL='TRUE';
      INPUT_LOAD='(-0.01,0.01)';
      OUTPUT_LOAD='(1.0,-1.0)';
    'GPIOV1||SIOS5#':
      PIN_NUMBER='(0,AF14,0,0,0,0)';
      BIDIRECTIONAL='TRUE';
      INPUT_LOAD='(-0.01,0.01)';
      OUTPUT_LOAD='(1.0,-1.0)';
    'GPIOV2||SIOPWREQ#':
      PIN_NUMBER='(0,AD14,0,0,0,0)';
      BIDIRECTIONAL='TRUE';
      INPUT_LOAD='(-0.01,0.01)';
      OUTPUT_LOAD='(1.0,-1.0)';
    'GPIOV3||SIOONCTRL#':
      PIN_NUMBER='(0,AC15,0,0,0,0)';
      BIDIRECTIONAL='TRUE';
      INPUT_LOAD='(-0.01,0.01)';
      OUTPUT_LOAD='(1.0,-1.0)';
    'GPIOV4||SIOPWRGD':
      PIN_NUMBER='(0,AE15,0,0,0,0)';
      BIDIRECTIONAL='TRUE';
      INPUT_LOAD='(-0.01,0.01)';
      OUTPUT_LOAD='(1.0,-1.0)';
    'GPIOV5||LPCPD#':
      PIN_NUMBER='(0,AE14,0,0,0,0)';
      BIDIRECTIONAL='TRUE';
      INPUT_LOAD='(-0.01,0.01)';
      OUTPUT_LOAD='(1.0,-1.0)';
    'GPIOV6||LPCPME#':
      PIN_NUMBER='(0,AD15,0,0,0,0)';
      BIDIRECTIONAL='TRUE';
      INPUT_LOAD='(-0.01,0.01)';
      OUTPUT_LOAD='(1.0,-1.0)';
    'GPIOV7||LPCSMI#':
      PIN_NUMBER='(0,AF15,0,0,0,0)';
      BIDIRECTIONAL='TRUE';
      INPUT_LOAD='(-0.01,0.01)';
      OUTPUT_LOAD='(1.0,-1.0)';
    'FWSPICK':
      PIN_NUMBER='(0,AF13,0,0,0,0)';
      OUTPUT_LOAD='(1.0,-1.0)';
    'FWSPIMOSI':
      PIN_NUMBER='(0,AC14,0,0,0,0)';
      BIDIRECTIONAL='TRUE';
      INPUT_LOAD='(-0.01,0.01)';
      OUTPUT_LOAD='(1.0,-1.0)';
    'FWSPIMISO':
      PIN_NUMBER='(0,AB13,0,0,0,0)';
      BIDIRECTIONAL='TRUE';
      INPUT_LOAD='(-0.01,0.01)';
      OUTPUT_LOAD='(1.0,-1.0)';
    'GPIOY5||FWSPIDQ3':
      PIN_NUMBER='(0,AF12,0,0,0,0)';
      BIDIRECTIONAL='TRUE';
      INPUT_LOAD='(-0.01,0.01)';
      OUTPUT_LOAD='(1.0,-1.0)';
    'GPIOY4||FWSPIDQ2':
      PIN_NUMBER='(0,AE12,0,0,0,0)';
      BIDIRECTIONAL='TRUE';
      INPUT_LOAD='(-0.01,0.01)';
      OUTPUT_LOAD='(1.0,-1.0)';
    'GPIOY6||FWSPIABR':
      PIN_NUMBER='(0,AC12,0,0,0,0)';
      BIDIRECTIONAL='TRUE';
      INPUT_LOAD='(-0.01,0.01)';
      OUTPUT_LOAD='(1.0,-1.0)';
    'GPIOY7||FWSPIWP#':
      PIN_NUMBER='(0,AB12,0,0,0,0)';
      BIDIRECTIONAL='TRUE';
      INPUT_LOAD='(-0.01,0.01)';
      OUTPUT_LOAD='(1.0,-1.0)';
    'GPIOZ3||SPI1CK':
      PIN_NUMBER='(0,AB11,0,0,0,0)';
      BIDIRECTIONAL='TRUE';
      INPUT_LOAD='(-0.01,0.01)';
      OUTPUT_LOAD='(1.0,-1.0)';
    'GPIOZ4||SPI1MOSI':
      PIN_NUMBER='(0,AC11,0,0,0,0)';
      BIDIRECTIONAL='TRUE';
      INPUT_LOAD='(-0.01,0.01)';
      OUTPUT_LOAD='(1.0,-1.0)';
    'GPIOZ5||SPI1MISO':
      PIN_NUMBER='(0,AA11,0,0,0,0)';
      BIDIRECTIONAL='TRUE';
      INPUT_LOAD='(-0.01,0.01)';
      OUTPUT_LOAD='(1.0,-1.0)';
    'GPIOZ6||SPI1DQ2||TXD13':
      PIN_NUMBER='(0,AD11,0,0,0,0)';
      BIDIRECTIONAL='TRUE';
      INPUT_LOAD='(-0.01,0.01)';
      OUTPUT_LOAD='(1.0,-1.0)';
    'GPIOZ7||SPI1DQ3||RXD13':
      PIN_NUMBER='(0,AF10,0,0,0,0)';
      BIDIRECTIONAL='TRUE';
      INPUT_LOAD='(-0.01,0.01)';
      OUTPUT_LOAD='(1.0,-1.0)';
    'SPI1CS0#':
      PIN_NUMBER='(0,AD13,0,0,0,0)';
      OUTPUT_LOAD='(1.0,-1.0)';
    'GPIOZ0||SPI1CS1#':
      PIN_NUMBER='(0,AC10,0,0,0,0)';
      BIDIRECTIONAL='TRUE';
      INPUT_LOAD='(-0.01,0.01)';
      OUTPUT_LOAD='(1.0,-1.0)';
    'GPIOZ1||SPI1ABR':
      PIN_NUMBER='(0,AD10,0,0,0,0)';
      BIDIRECTIONAL='TRUE';
      INPUT_LOAD='(-0.01,0.01)';
      OUTPUT_LOAD='(1.0,-1.0)';
    'GPIOZ2||SPI1WP#':
      PIN_NUMBER='(0,AE10,0,0,0,0)';
      BIDIRECTIONAL='TRUE';
      INPUT_LOAD='(-0.01,0.01)';
      OUTPUT_LOAD='(1.0,-1.0)';
    'GPIOX3||SPI2CK':
      PIN_NUMBER='(0,AF8,0,0,0,0)';
      BIDIRECTIONAL='TRUE';
      INPUT_LOAD='(-0.01,0.01)';
      OUTPUT_LOAD='(1.0,-1.0)';
    'GPIOX4||SPI2MOSI':
      PIN_NUMBER='(0,AB9,0,0,0,0)';
      BIDIRECTIONAL='TRUE';
      INPUT_LOAD='(-0.01,0.01)';
      OUTPUT_LOAD='(1.0,-1.0)';
    'GPIOX5||SPI2MISO':
      PIN_NUMBER='(0,AD9,0,0,0,0)';
      BIDIRECTIONAL='TRUE';
      INPUT_LOAD='(-0.01,0.01)';
      OUTPUT_LOAD='(1.0,-1.0)';
    'GPIOX6||SPI2DQ2||TXD12':
      PIN_NUMBER='(0,AF9,0,0,0,0)';
      BIDIRECTIONAL='TRUE';
      INPUT_LOAD='(-0.01,0.01)';
      OUTPUT_LOAD='(1.0,-1.0)';
    'GPIOX7||SPI2DQ3||RXD12':
      PIN_NUMBER='(0,AB10,0,0,0,0)';
      BIDIRECTIONAL='TRUE';
      INPUT_LOAD='(-0.01,0.01)';
      OUTPUT_LOAD='(1.0,-1.0)';
    'GPIOX0||SPI2CS0#':
      PIN_NUMBER='(0,AE8,0,0,0,0)';
      BIDIRECTIONAL='TRUE';
      INPUT_LOAD='(-0.01,0.01)';
      OUTPUT_LOAD='(1.0,-1.0)';
    'GPIOX1||SPI2CS1#':
      PIN_NUMBER='(0,AA9,0,0,0,0)';
      BIDIRECTIONAL='TRUE';
      INPUT_LOAD='(-0.01,0.01)';
      OUTPUT_LOAD='(1.0,-1.0)';
    'GPIOX2||SPI2CS2#':
      PIN_NUMBER='(0,AC9,0,0,0,0)';
      BIDIRECTIONAL='TRUE';
      INPUT_LOAD='(-0.01,0.01)';
      OUTPUT_LOAD='(1.0,-1.0)';
    'GPIOB0||SALT1':
      PIN_NUMBER='(0,J26,0,0,0,0)';
      BIDIRECTIONAL='TRUE';
      INPUT_LOAD='(-0.01,0.01)';
      OUTPUT_LOAD='(1.0,-1.0)';
    'GPIOB1||SALT2':
      PIN_NUMBER='(0,K23,0,0,0,0)';
      BIDIRECTIONAL='TRUE';
      INPUT_LOAD='(-0.01,0.01)';
      OUTPUT_LOAD='(1.0,-1.0)';
    'GPIOB2||SALT3':
      PIN_NUMBER='(0,H26,0,0,0,0)';
      BIDIRECTIONAL='TRUE';
      INPUT_LOAD='(-0.01,0.01)';
      OUTPUT_LOAD='(1.0,-1.0)';
    'GPIOB3||SALT4':
      PIN_NUMBER='(0,J25,0,0,0,0)';
      BIDIRECTIONAL='TRUE';
      INPUT_LOAD='(-0.01,0.01)';
      OUTPUT_LOAD='(1.0,-1.0)';
    'GPIOB4||MDC2':
      PIN_NUMBER='(0,J23,0,0,0,0)';
      BIDIRECTIONAL='TRUE';
      INPUT_LOAD='(-0.01,0.01)';
      OUTPUT_LOAD='(1.0,-1.0)';
    'GPIOB5||MDIO2':
      PIN_NUMBER='(0,G26,0,0,0,0)';
      BIDIRECTIONAL='TRUE';
      INPUT_LOAD='(-0.01,0.01)';
      OUTPUT_LOAD='(1.0,-1.0)';
    'GPIOB6||TXD4':
      PIN_NUMBER='(0,H25,0,0,0,0)';
      BIDIRECTIONAL='TRUE';
      INPUT_LOAD='(-0.01,0.01)';
      OUTPUT_LOAD='(1.0,-1.0)';
    'GPIOB7||RXD4':
      PIN_NUMBER='(0,J24,0,0,0,0)';
      BIDIRECTIONAL='TRUE';
      INPUT_LOAD='(-0.01,0.01)';
      OUTPUT_LOAD='(1.0,-1.0)';
    'GPIOY0||SALT5||WDTRST1#':
      PIN_NUMBER='(0,AF11,0,0,0,0)';
      BIDIRECTIONAL='TRUE';
      INPUT_LOAD='(-0.01,0.01)';
      OUTPUT_LOAD='(1.0,-1.0)';
    'GPIOY1||SALT6||WDTRST2#':
      PIN_NUMBER='(0,AD12,0,0,0,0)';
      BIDIRECTIONAL='TRUE';
      INPUT_LOAD='(-0.01,0.01)';
      OUTPUT_LOAD='(1.0,-1.0)';
    'GPIOY2||SALT7||WDTRST3#':
      PIN_NUMBER='(0,AE11,0,0,0,0)';
      BIDIRECTIONAL='TRUE';
      INPUT_LOAD='(-0.01,0.01)';
      OUTPUT_LOAD='(1.0,-1.0)';
    'GPIOY3||SALT8||WDTRST4#':
      PIN_NUMBER='(0,AA12,0,0,0,0)';
      BIDIRECTIONAL='TRUE';
      INPUT_LOAD='(-0.01,0.01)';
      OUTPUT_LOAD='(1.0,-1.0)';
    'TXD5':
      PIN_NUMBER='(0,C8,0,0,0,0)';
      OUTPUT_LOAD='(1.0,-1.0)';
    'RXD5':
      PIN_NUMBER='(0,D8,0,0,0,0)';
      INPUT_LOAD='(-0.01,0.01)';
    'RGMII3RXCK||RMII3RCLKI||GPIOC6':
      PIN_NUMBER='(0,G23,0,0,0,0)';
      BIDIRECTIONAL='TRUE';
      INPUT_LOAD='(-0.01,0.01)';
      OUTPUT_LOAD='(1.0,-1.0)';
    'RGMII3RXCTL||GPIOC7':
      PIN_NUMBER='(0,G24,0,0,0,0)';
      BIDIRECTIONAL='TRUE';
      INPUT_LOAD='(-0.01,0.01)';
      OUTPUT_LOAD='(1.0,-1.0)';
    'RGMII3RXD0||RMII3RXD0||GPIOD0':
      PIN_NUMBER='(0,F23,0,0,0,0)';
      BIDIRECTIONAL='TRUE';
      INPUT_LOAD='(-0.01,0.01)';
      OUTPUT_LOAD='(1.0,-1.0)';
    'RGMII3RXD1||RMII3RXD1||GPIOD1':
      PIN_NUMBER='(0,F26,0,0,0,0)';
      BIDIRECTIONAL='TRUE';
      INPUT_LOAD='(-0.01,0.01)';
      OUTPUT_LOAD='(1.0,-1.0)';
    'RGMII3RXD2||RMII3CRSDV||GPIOD2':
      PIN_NUMBER='(0,F25,0,0,0,0)';
      BIDIRECTIONAL='TRUE';
      INPUT_LOAD='(-0.01,0.01)';
      OUTPUT_LOAD='(1.0,-1.0)';
    'RGMII3RXD3||RMII3RXER||GPIOD3':
      PIN_NUMBER='(0,E26,0,0,0,0)';
      BIDIRECTIONAL='TRUE';
      INPUT_LOAD='(-0.01,0.01)';
      OUTPUT_LOAD='(1.0,-1.0)';
    'RGMII4RXCK||RMII4RCLKI||NCTS4||GPIOE2':
      PIN_NUMBER='(0,C25,0,0,0,0)';
      BIDIRECTIONAL='TRUE';
      INPUT_LOAD='(-0.01,0.01)';
      OUTPUT_LOAD='(1.0,-1.0)';
    'RGMII4RXCTL||NDCD4||GPIOE3':
      PIN_NUMBER='(0,C26,0,0,0,0)';
      BIDIRECTIONAL='TRUE';
      INPUT_LOAD='(-0.01,0.01)';
      OUTPUT_LOAD='(1.0,-1.0)';
    'RGMII4RXD0||RMII4RXD0||NDSR4||GPIOE4':
      PIN_NUMBER='(0,C24,0,0,0,0)';
      BIDIRECTIONAL='TRUE';
      INPUT_LOAD='(-0.01,0.01)';
      OUTPUT_LOAD='(1.0,-1.0)';
    'RGMII4RXD1||RMII4RXD1||NRI4||GPIOE5':
      PIN_NUMBER='(0,B26,0,0,0,0)';
      BIDIRECTIONAL='TRUE';
      INPUT_LOAD='(-0.01,0.01)';
      OUTPUT_LOAD='(1.0,-1.0)';
    'RGMII4RXD2||RMII4CRSDV||NDTR4||GPIOE6':
      PIN_NUMBER='(0,B25,0,0,0,0)';
      BIDIRECTIONAL='TRUE';
      INPUT_LOAD='(-0.01,0.01)';
      OUTPUT_LOAD='(1.0,-1.0)';
    'RGMII4RXD3||RMII4RXER||NRTS4||GPIOE7':
      PIN_NUMBER='(0,B24,0,0,0,0)';
      BIDIRECTIONAL='TRUE';
      INPUT_LOAD='(-0.01,0.01)';
      OUTPUT_LOAD='(1.0,-1.0)';
    'RGMII4TXCK||RMII4RCLKO||NCTS3||GPIOD4':
      PIN_NUMBER='(0,F24,0,0,0,0)';
      BIDIRECTIONAL='TRUE';
      INPUT_LOAD='(-0.01,0.01)';
      OUTPUT_LOAD='(1.0,-1.0)';
    'RGMII4TXCTL||RMII4TXEN||NDCD3||GPIOD5':
      PIN_NUMBER='(0,E23,0,0,0,0)';
      BIDIRECTIONAL='TRUE';
      INPUT_LOAD='(-0.01,0.01)';
      OUTPUT_LOAD='(1.0,-1.0)';
    'RGMII4TXD0||RMII4TXD0||NDSR3||GPIOD6':
      PIN_NUMBER='(0,E24,0,0,0,0)';
      BIDIRECTIONAL='TRUE';
      INPUT_LOAD='(-0.01,0.01)';
      OUTPUT_LOAD='(1.0,-1.0)';
    'RGMII4TXD1||RMII4TXD1||NRI3||GPIOD7':
      PIN_NUMBER='(0,E25,0,0,0,0)';
      BIDIRECTIONAL='TRUE';
      INPUT_LOAD='(-0.01,0.01)';
      OUTPUT_LOAD='(1.0,-1.0)';
    'RGMII4TXD2||NDTR3||GPIOE0':
      PIN_NUMBER='(0,D26,0,0,0,0)';
      BIDIRECTIONAL='TRUE';
      INPUT_LOAD='(-0.01,0.01)';
      OUTPUT_LOAD='(1.0,-1.0)';
    'RGMII4TXD3||NRTS3||GPIOE1':
      PIN_NUMBER='(0,D24,0,0,0,0)';
      BIDIRECTIONAL='TRUE';
      INPUT_LOAD='(-0.01,0.01)';
      OUTPUT_LOAD='(1.0,-1.0)';
    'RGMII3TXCK||RMII3RCLKO||GPIOC0':
      PIN_NUMBER='(0,H24,0,0,0,0)';
      BIDIRECTIONAL='TRUE';
      INPUT_LOAD='(-0.01,0.01)';
      OUTPUT_LOAD='(1.0,-1.0)';
    'RGMII3TXCTL||RMII3TXEN||GPIOC1':
      PIN_NUMBER='(0,J22,0,0,0,0)';
      BIDIRECTIONAL='TRUE';
      INPUT_LOAD='(-0.01,0.01)';
      OUTPUT_LOAD='(1.0,-1.0)';
    'RGMII3TXD0||RMII3TXD0||GPIOC2':
      PIN_NUMBER='(0,H22,0,0,0,0)';
      BIDIRECTIONAL='TRUE';
      INPUT_LOAD='(-0.01,0.01)';
      OUTPUT_LOAD='(1.0,-1.0)';
    'RGMII3TXD1||RMII3TXD1||GPIOC3':
      PIN_NUMBER='(0,H23,0,0,0,0)';
      BIDIRECTIONAL='TRUE';
      INPUT_LOAD='(-0.01,0.01)';
      OUTPUT_LOAD='(1.0,-1.0)';
    'RGMII3TXD2||GPIOC4':
      PIN_NUMBER='(0,G22,0,0,0,0)';
      BIDIRECTIONAL='TRUE';
      INPUT_LOAD='(-0.01,0.01)';
      OUTPUT_LOAD='(1.0,-1.0)';
    'RGMII3TXD3||GPIOC5':
      PIN_NUMBER='(0,F22,0,0,0,0)';
      BIDIRECTIONAL='TRUE';
      INPUT_LOAD='(-0.01,0.01)';
      OUTPUT_LOAD='(1.0,-1.0)';
    'RGMIICK':
      PIN_NUMBER='(0,A10,0,0,0,0)';
      INPUT_LOAD='(-0.01,0.01)';
    'GPIOS0||MDC1':
      PIN_NUMBER='(0,R23,0,0,0,0)';
      BIDIRECTIONAL='TRUE';
      INPUT_LOAD='(-0.01,0.01)';
      OUTPUT_LOAD='(1.0,-1.0)';
    'GPIOS1||MDIO1':
      PIN_NUMBER='(0,T25,0,0,0,0)';
      BIDIRECTIONAL='TRUE';
      INPUT_LOAD='(-0.01,0.01)';
      OUTPUT_LOAD='(1.0,-1.0)';
    'GPIOS5||RXD10':
      PIN_NUMBER='(0,P24,0,0,0,0)';
      BIDIRECTIONAL='TRUE';
      INPUT_LOAD='(-0.01,0.01)';
      OUTPUT_LOAD='(1.0,-1.0)';
    'GPIOS6||TXD11':
      PIN_NUMBER='(0,P23,0,0,0,0)';
      BIDIRECTIONAL='TRUE';
      INPUT_LOAD='(-0.01,0.01)';
      OUTPUT_LOAD='(1.0,-1.0)';
    'GPIOS7||RXD11':
      PIN_NUMBER='(0,T24,0,0,0,0)';
      BIDIRECTIONAL='TRUE';
      INPUT_LOAD='(-0.01,0.01)';
      OUTPUT_LOAD='(1.0,-1.0)';
    'GPIOS4||TXD10':
      PIN_NUMBER='(0,R26,0,0,0,0)';
      BIDIRECTIONAL='TRUE';
      INPUT_LOAD='(-0.01,0.01)';
      OUTPUT_LOAD='(1.0,-1.0)';
    'GPIOI6||SIOPBI#':
      PIN_NUMBER='(0,B16,0,0,0,0)';
      BIDIRECTIONAL='TRUE';
      INPUT_LOAD='(-0.01,0.01)';
      OUTPUT_LOAD='(1.0,-1.0)';
    'GPIOI5||SIOPBO#':
      PIN_NUMBER='(0,E16,0,0,0,0)';
      BIDIRECTIONAL='TRUE';
      INPUT_LOAD='(-0.01,0.01)';
      OUTPUT_LOAD='(1.0,-1.0)';
    'GPIOI7||SIOSCI#':
      PIN_NUMBER='(0,A15,0,0,0,0)';
      BIDIRECTIONAL='TRUE';
      INPUT_LOAD='(-0.01,0.01)';
      OUTPUT_LOAD='(1.0,-1.0)';
    'RGMII1RXCK||RMII1RCLKI||GPIO18A6':
      PIN_NUMBER='(0,0,B3,0,0,0)';
      BIDIRECTIONAL='TRUE';
      INPUT_LOAD='(-0.01,0.01)';
      OUTPUT_LOAD='(1.0,-1.0)';
    'RGMII1RXCTL||GPIO18A7':
      PIN_NUMBER='(0,0,A2,0,0,0)';
      BIDIRECTIONAL='TRUE';
      INPUT_LOAD='(-0.01,0.01)';
      OUTPUT_LOAD='(1.0,-1.0)';
    'RGMII1RXD0||RMII1RXD0||GPIO18B0':
      PIN_NUMBER='(0,0,B2,0,0,0)';
      BIDIRECTIONAL='TRUE';
      INPUT_LOAD='(-0.01,0.01)';
      OUTPUT_LOAD='(1.0,-1.0)';
    'RGMII1RXD1||RMII1RXD1||GPIO18B1':
      PIN_NUMBER='(0,0,B1,0,0,0)';
      BIDIRECTIONAL='TRUE';
      INPUT_LOAD='(-0.01,0.01)';
      OUTPUT_LOAD='(1.0,-1.0)';
    'RGMII1RXD2||RMII1CRSDV||GPIO18B2':
      PIN_NUMBER='(0,0,C4,0,0,0)';
      BIDIRECTIONAL='TRUE';
      INPUT_LOAD='(-0.01,0.01)';
      OUTPUT_LOAD='(1.0,-1.0)';
    'RGMII1RXD3||RMII1RXER||GPIO18B3':
      PIN_NUMBER='(0,0,E5,0,0,0)';
      BIDIRECTIONAL='TRUE';
      INPUT_LOAD='(-0.01,0.01)';
      OUTPUT_LOAD='(1.0,-1.0)';
    'RGMII1TXCK||RMII1RCLKO||GPIO18A0':
      PIN_NUMBER='(0,0,C6,0,0,0)';
      BIDIRECTIONAL='TRUE';
      INPUT_LOAD='(-0.01,0.01)';
      OUTPUT_LOAD='(1.0,-1.0)';
    'RGMII1TXCTL||RMII1TXEN||GPIO18A1':
      PIN_NUMBER='(0,0,D6,0,0,0)';
      BIDIRECTIONAL='TRUE';
      INPUT_LOAD='(-0.01,0.01)';
      OUTPUT_LOAD='(1.0,-1.0)';
    'RGMII1TXD0||RMII1TXD0||GPIO18A2':
      PIN_NUMBER='(0,0,D5,0,0,0)';
      BIDIRECTIONAL='TRUE';
      INPUT_LOAD='(-0.01,0.01)';
      OUTPUT_LOAD='(1.0,-1.0)';
    'RGMII1TXD1||RMII1TXD1||GPIO18A3':
      PIN_NUMBER='(0,0,A3,0,0,0)';
      BIDIRECTIONAL='TRUE';
      INPUT_LOAD='(-0.01,0.01)';
      OUTPUT_LOAD='(1.0,-1.0)';
    'RGMII1TXD2||GPIO18A4':
      PIN_NUMBER='(0,0,C5,0,0,0)';
      BIDIRECTIONAL='TRUE';
      INPUT_LOAD='(-0.01,0.01)';
      OUTPUT_LOAD='(1.0,-1.0)';
    'RGMII1TXD3||GPIO18A5':
      PIN_NUMBER='(0,0,E6,0,0,0)';
      BIDIRECTIONAL='TRUE';
      INPUT_LOAD='(-0.01,0.01)';
      OUTPUT_LOAD='(1.0,-1.0)';
    'RGMII2RXCK||RMII2RCLKI||GPIO18C2':
      PIN_NUMBER='(0,0,D2,0,0,0)';
      BIDIRECTIONAL='TRUE';
      INPUT_LOAD='(-0.01,0.01)';
      OUTPUT_LOAD='(1.0,-1.0)';
    'RGMII2RXCTL||GPIO18C3':
      PIN_NUMBER='(0,0,E3,0,0,0)';
      BIDIRECTIONAL='TRUE';
      INPUT_LOAD='(-0.01,0.01)';
      OUTPUT_LOAD='(1.0,-1.0)';
    'RGMII2RXD0||RMII2RXD0||GPIO18C4':
      PIN_NUMBER='(0,0,D1,0,0,0)';
      BIDIRECTIONAL='TRUE';
      INPUT_LOAD='(-0.01,0.01)';
      OUTPUT_LOAD='(1.0,-1.0)';
    'RGMII2RXD1||RMII2RXD1||GPIO18C5':
      PIN_NUMBER='(0,0,F4,0,0,0)';
      BIDIRECTIONAL='TRUE';
      INPUT_LOAD='(-0.01,0.01)';
      OUTPUT_LOAD='(1.0,-1.0)';
    'RGMII2RXD2||RMII2CRSDV||GPIO18C6':
      PIN_NUMBER='(0,0,E2,0,0,0)';
      BIDIRECTIONAL='TRUE';
      INPUT_LOAD='(-0.01,0.01)';
      OUTPUT_LOAD='(1.0,-1.0)';
    'RGMII2RXD3||RMII2RXER||GPIO18C7':
      PIN_NUMBER='(0,0,E1,0,0,0)';
      BIDIRECTIONAL='TRUE';
      INPUT_LOAD='(-0.01,0.01)';
      OUTPUT_LOAD='(1.0,-1.0)';
    'RGMII2TXCK||RMII2RCLKO||GPIO18B4':
      PIN_NUMBER='(0,0,D4,0,0,0)';
      BIDIRECTIONAL='TRUE';
      INPUT_LOAD='(-0.01,0.01)';
      OUTPUT_LOAD='(1.0,-1.0)';
    'RGMII2TXCTL||RMII2TXEN||GPIO18B5':
      PIN_NUMBER='(0,0,C2,0,0,0)';
      BIDIRECTIONAL='TRUE';
      INPUT_LOAD='(-0.01,0.01)';
      OUTPUT_LOAD='(1.0,-1.0)';
    'RGMII2TXD0||RMII2TXD0||GPIO18B6':
      PIN_NUMBER='(0,0,C1,0,0,0)';
      BIDIRECTIONAL='TRUE';
      INPUT_LOAD='(-0.01,0.01)';
      OUTPUT_LOAD='(1.0,-1.0)';
    'RGMII2TXD1||RMII2TXD1||GPIO18B7':
      PIN_NUMBER='(0,0,D3,0,0,0)';
      BIDIRECTIONAL='TRUE';
      INPUT_LOAD='(-0.01,0.01)';
      OUTPUT_LOAD='(1.0,-1.0)';
    'RGMII2TXD2||GPIO18C0':
      PIN_NUMBER='(0,0,E4,0,0,0)';
      BIDIRECTIONAL='TRUE';
      INPUT_LOAD='(-0.01,0.01)';
      OUTPUT_LOAD='(1.0,-1.0)';
    'RGMII2TXD3||GPIO18C1':
      PIN_NUMBER='(0,0,F5,0,0,0)';
      BIDIRECTIONAL='TRUE';
      INPUT_LOAD='(-0.01,0.01)';
      OUTPUT_LOAD='(1.0,-1.0)';
    'GPIO18D0||EMMCCLK':
      PIN_NUMBER='(0,0,AB4,0,0,0)';
      BIDIRECTIONAL='TRUE';
      INPUT_LOAD='(-0.01,0.01)';
      OUTPUT_LOAD='(1.0,-1.0)';
    'GPIO18D1||EMMCCMD':
      PIN_NUMBER='(0,0,AA4,0,0,0)';
      BIDIRECTIONAL='TRUE';
      INPUT_LOAD='(-0.01,0.01)';
      OUTPUT_LOAD='(1.0,-1.0)';
    'GPIO18D2||EMMCDAT0':
      PIN_NUMBER='(0,0,AC4,0,0,0)';
      BIDIRECTIONAL='TRUE';
      INPUT_LOAD='(-0.01,0.01)';
      OUTPUT_LOAD='(1.0,-1.0)';
    'GPIO18D3||EMMCDAT1':
      PIN_NUMBER='(0,0,AA5,0,0,0)';
      BIDIRECTIONAL='TRUE';
      INPUT_LOAD='(-0.01,0.01)';
      OUTPUT_LOAD='(1.0,-1.0)';
    'GPIO18D4||EMMCDAT2':
      PIN_NUMBER='(0,0,Y5,0,0,0)';
      BIDIRECTIONAL='TRUE';
      INPUT_LOAD='(-0.01,0.01)';
      OUTPUT_LOAD='(1.0,-1.0)';
    'GPIO18D5||EMMCDAT3':
      PIN_NUMBER='(0,0,AB5,0,0,0)';
      BIDIRECTIONAL='TRUE';
      INPUT_LOAD='(-0.01,0.01)';
      OUTPUT_LOAD='(1.0,-1.0)';
    'GPIO18D6||EMMCCD#':
      PIN_NUMBER='(0,0,AC5,0,0,0)';
      BIDIRECTIONAL='TRUE';
      INPUT_LOAD='(-0.01,0.01)';
      OUTPUT_LOAD='(1.0,-1.0)';
    'GPIO18D7||EMMCWP#':
      PIN_NUMBER='(0,0,AB6,0,0,0)';
      BIDIRECTIONAL='TRUE';
      INPUT_LOAD='(-0.01,0.01)';
      OUTPUT_LOAD='(1.0,-1.0)';
    'GPIO18E0||EMMCDAT4||FWSPI18CS#||VBCS#':
      PIN_NUMBER='(0,0,Y1,0,0,0)';
      BIDIRECTIONAL='TRUE';
      INPUT_LOAD='(-0.01,0.01)';
      OUTPUT_LOAD='(1.0,-1.0)';
    'GPIO18E1||EMMCDAT5||FWSPI18CK||VBCK':
      PIN_NUMBER='(0,0,Y2,0,0,0)';
      BIDIRECTIONAL='TRUE';
      INPUT_LOAD='(-0.01,0.01)';
      OUTPUT_LOAD='(1.0,-1.0)';
    'GPIO18E2||EMMCDAT6||FWSPI18MOSI||VBMOSI':
      PIN_NUMBER='(0,0,Y3,0,0,0)';
      BIDIRECTIONAL='TRUE';
      INPUT_LOAD='(-0.01,0.01)';
      OUTPUT_LOAD='(1.0,-1.0)';
    'GPIO18E3||EMMCDAT7||FWSPI18MISO||VBMISO':
      PIN_NUMBER='(0,0,Y4,0,0,0)';
      BIDIRECTIONAL='TRUE';
      INPUT_LOAD='(-0.01,0.01)';
      OUTPUT_LOAD='(1.0,-1.0)';
    'I3C1SCL':
      PIN_NUMBER='(0,0,AF23,0,0,0)';
      BIDIRECTIONAL='TRUE';
      INPUT_LOAD='(-0.01,0.01)';
      OUTPUT_LOAD='(1.0,-1.0)';
    'I3C1SDA':
      PIN_NUMBER='(0,0,AE24,0,0,0)';
      BIDIRECTIONAL='TRUE';
      INPUT_LOAD='(-0.01,0.01)';
      OUTPUT_LOAD='(1.0,-1.0)';
    'I3C2SCL':
      PIN_NUMBER='(0,0,AF22,0,0,0)';
      BIDIRECTIONAL='TRUE';
      INPUT_LOAD='(-0.01,0.01)';
      OUTPUT_LOAD='(1.0,-1.0)';
    'I3C2SDA':
      PIN_NUMBER='(0,0,AE22,0,0,0)';
      BIDIRECTIONAL='TRUE';
      INPUT_LOAD='(-0.01,0.01)';
      OUTPUT_LOAD='(1.0,-1.0)';
    'I3C3SCL||FSI1CLK':
      PIN_NUMBER='(0,0,AF25,0,0,0)';
      BIDIRECTIONAL='TRUE';
      INPUT_LOAD='(-0.01,0.01)';
      OUTPUT_LOAD='(1.0,-1.0)';
    'I3C3SDA||FSI1DATA':
      PIN_NUMBER='(0,0,AE26,0,0,0)';
      BIDIRECTIONAL='TRUE';
      INPUT_LOAD='(-0.01,0.01)';
      OUTPUT_LOAD='(1.0,-1.0)';
    'I3C4SCL||FSI2CLK':
      PIN_NUMBER='(0,0,AE25,0,0,0)';
      BIDIRECTIONAL='TRUE';
      INPUT_LOAD='(-0.01,0.01)';
      OUTPUT_LOAD='(1.0,-1.0)';
    'I3C4SDA||FSI2DATA':
      PIN_NUMBER='(0,0,AF24,0,0,0)';
      BIDIRECTIONAL='TRUE';
      INPUT_LOAD='(-0.01,0.01)';
      OUTPUT_LOAD='(1.0,-1.0)';
    'DACB':
      PIN_NUMBER='(0,0,0,AD21,0,0)';
      OUTPUT_LOAD='(1.0,-1.0)';
    'DACG':
      PIN_NUMBER='(0,0,0,AE21,0,0)';
      OUTPUT_LOAD='(1.0,-1.0)';
    'DACR':
      PIN_NUMBER='(0,0,0,AF21,0,0)';
      OUTPUT_LOAD='(1.0,-1.0)';
    'USB2AV33':
      PIN_NUMBER='(0,0,0,J10,0,0)';
      PINUSE='POWER';
      NO_LOAD_CHECK='Both';
      NO_IO_CHECK='Both';
      NO_ASSERT_CHECK='TRUE';
      NO_DIR_CHECK='TRUE';
      ALLOW_CONNECT='TRUE';
    'USB2A_DN':
      PIN_NUMBER='(0,0,0,B4,0,0)';
      BIDIRECTIONAL='TRUE';
      INPUT_LOAD='(-0.01,0.01)';
      OUTPUT_LOAD='(1.0,-1.0)';
    'USB2A_DP':
      PIN_NUMBER='(0,0,0,A4,0,0)';
      BIDIRECTIONAL='TRUE';
      INPUT_LOAD='(-0.01,0.01)';
      OUTPUT_LOAD='(1.0,-1.0)';
    'USB2B_DN':
      PIN_NUMBER='(0,0,0,B6,0,0)';
      BIDIRECTIONAL='TRUE';
      INPUT_LOAD='(-0.01,0.01)';
      OUTPUT_LOAD='(1.0,-1.0)';
    'USB2B_DP':
      PIN_NUMBER='(0,0,0,A6,0,0)';
      BIDIRECTIONAL='TRUE';
      INPUT_LOAD='(-0.01,0.01)';
      OUTPUT_LOAD='(1.0,-1.0)';
    'ADC0||GPIT0':
      PIN_NUMBER='(0,0,0,AD20,0,0)';
      INPUT_LOAD='(-0.01,0.01)';
    'ADC1||GPIT1':
      PIN_NUMBER='(0,0,0,AC18,0,0)';
      INPUT_LOAD='(-0.01,0.01)';
    'ADC2||GPIT2':
      PIN_NUMBER='(0,0,0,AE19,0,0)';
      INPUT_LOAD='(-0.01,0.01)';
    'ADC3||GPIT3':
      PIN_NUMBER='(0,0,0,AD19,0,0)';
      INPUT_LOAD='(-0.01,0.01)';
    'ADC4||GPIT4':
      PIN_NUMBER='(0,0,0,AC19,0,0)';
      INPUT_LOAD='(-0.01,0.01)';
    'ADC5||GPIT5':
      PIN_NUMBER='(0,0,0,AB19,0,0)';
      INPUT_LOAD='(-0.01,0.01)';
    'ADC6||GPIT6':
      PIN_NUMBER='(0,0,0,AB18,0,0)';
      INPUT_LOAD='(-0.01,0.01)';
    'ADC7||GPIT7':
      PIN_NUMBER='(0,0,0,AE18,0,0)';
      INPUT_LOAD='(-0.01,0.01)';
    'ADC8||GPIU0||SALT9':
      PIN_NUMBER='(0,0,0,AB16,0,0)';
      INPUT_LOAD='(-0.01,0.01)';
    'ADC9||GPIU1||SALT10':
      PIN_NUMBER='(0,0,0,AA17,0,0)';
      INPUT_LOAD='(-0.01,0.01)';
    'ADC10||GPIU2||SALT11':
      PIN_NUMBER='(0,0,0,AB17,0,0)';
      INPUT_LOAD='(-0.01,0.01)';
    'ADC11||GPIU3||SALT12':
      PIN_NUMBER='(0,0,0,AE16,0,0)';
      INPUT_LOAD='(-0.01,0.01)';
    'ADC12||GPIU4||SALT13':
      PIN_NUMBER='(0,0,0,AC16,0,0)';
      INPUT_LOAD='(-0.01,0.01)';
    'ADC13||GPIU5||SALT14':
      PIN_NUMBER='(0,0,0,AA16,0,0)';
      INPUT_LOAD='(-0.01,0.01)';
    'ADC14||GPIU6||SALT15':
      PIN_NUMBER='(0,0,0,AD16,0,0)';
      INPUT_LOAD='(-0.01,0.01)';
    'ADC15||GPIU7||SALT16':
      PIN_NUMBER='(0,0,0,AC17,0,0)';
      INPUT_LOAD='(-0.01,0.01)';
    'ENTEST':
      PIN_NUMBER='(0,0,0,C10,0,0)';
      INPUT_LOAD='(-0.01,0.01)';
    'SRST#':
      PIN_NUMBER='(0,0,0,E10,0,0)';
      INPUT_LOAD='(-0.01,0.01)';
    'EXTRST#':
      PIN_NUMBER='(0,0,0,B10,0,0)';
      INPUT_LOAD='(-0.01,0.01)';
    'CLKIN':
      PIN_NUMBER='(0,0,0,D10,0,0)';
      INPUT_LOAD='(-0.01,0.01)';
    'RSTIND#':
      PIN_NUMBER='(0,0,0,B7,0,0)';
      OUTPUT_LOAD='(1.0,-1.0)';
    'NTRST||MNTRST1':
      PIN_NUMBER='(0,0,0,F11,0,0)';
      BIDIRECTIONAL='TRUE';
      INPUT_LOAD='(-0.01,0.01)';
      OUTPUT_LOAD='(1.0,-1.0)';
    'TCK||MTCK1':
      PIN_NUMBER='(0,0,0,B9,0,0)';
      BIDIRECTIONAL='TRUE';
      INPUT_LOAD='(-0.01,0.01)';
      OUTPUT_LOAD='(1.0,-1.0)';
    'TDI||MTDI1':
      PIN_NUMBER='(0,0,0,D9,0,0)';
      BIDIRECTIONAL='TRUE';
      INPUT_LOAD='(-0.01,0.01)';
      OUTPUT_LOAD='(1.0,-1.0)';
    'TDO||MTDO1':
      PIN_NUMBER='(0,0,0,C9,0,0)';
      BIDIRECTIONAL='TRUE';
      INPUT_LOAD='(-0.01,0.01)';
      OUTPUT_LOAD='(1.0,-1.0)';
    'TMS||MTMS1':
      PIN_NUMBER='(0,0,0,A9,0,0)';
      BIDIRECTIONAL='TRUE';
      INPUT_LOAD='(-0.01,0.01)';
      OUTPUT_LOAD='(1.0,-1.0)';
    'GPIOL6||VGAHS':
      PIN_NUMBER='(0,0,0,B14,0,0)';
      BIDIRECTIONAL='TRUE';
      INPUT_LOAD='(-0.01,0.01)';
      OUTPUT_LOAD='(1.0,-1.0)';
    'GPIOL7||VGAVS':
      PIN_NUMBER='(0,0,0,C14,0,0)';
      BIDIRECTIONAL='TRUE';
      INPUT_LOAD='(-0.01,0.01)';
      OUTPUT_LOAD='(1.0,-1.0)';
    'DDCCLK':
      PIN_NUMBER='(0,0,0,B8,0,0)';
      OUTPUT_LOAD='(1.0,-1.0)';
    'DDCDAT':
      PIN_NUMBER='(0,0,0,A8,0,0)';
      OUTPUT_LOAD='(1.0,-1.0)';
    'GPIOO0||PWM0':
      PIN_NUMBER='(0,0,0,AD26,0,0)';
      BIDIRECTIONAL='TRUE';
      INPUT_LOAD='(-0.01,0.01)';
      OUTPUT_LOAD='(1.0,-1.0)';
    'GPIOO1||PWM1':
      PIN_NUMBER='(0,0,0,AD22,0,0)';
      BIDIRECTIONAL='TRUE';
      INPUT_LOAD='(-0.01,0.01)';
      OUTPUT_LOAD='(1.0,-1.0)';
    'GPIOO2||PWM2':
      PIN_NUMBER='(0,0,0,AD23,0,0)';
      BIDIRECTIONAL='TRUE';
      INPUT_LOAD='(-0.01,0.01)';
      OUTPUT_LOAD='(1.0,-1.0)';
    'GPIOO3||PWM3':
      PIN_NUMBER='(0,0,0,AD24,0,0)';
      BIDIRECTIONAL='TRUE';
      INPUT_LOAD='(-0.01,0.01)';
      OUTPUT_LOAD='(1.0,-1.0)';
    'GPIOO4||PWM4':
      PIN_NUMBER='(0,0,0,AD25,0,0)';
      BIDIRECTIONAL='TRUE';
      INPUT_LOAD='(-0.01,0.01)';
      OUTPUT_LOAD='(1.0,-1.0)';
    'GPIOO5||PWM5':
      PIN_NUMBER='(0,0,0,AC22,0,0)';
      BIDIRECTIONAL='TRUE';
      INPUT_LOAD='(-0.01,0.01)';
      OUTPUT_LOAD='(1.0,-1.0)';
    'GPIOO6||PWM6':
      PIN_NUMBER='(0,0,0,AC24,0,0)';
      BIDIRECTIONAL='TRUE';
      INPUT_LOAD='(-0.01,0.01)';
      OUTPUT_LOAD='(1.0,-1.0)';
    'GPIOO7||PWM7':
      PIN_NUMBER='(0,0,0,AC23,0,0)';
      BIDIRECTIONAL='TRUE';
      INPUT_LOAD='(-0.01,0.01)';
      OUTPUT_LOAD='(1.0,-1.0)';
    'GPIOQ0||TACH0':
      PIN_NUMBER='(0,0,0,AA25,0,0)';
      BIDIRECTIONAL='TRUE';
      INPUT_LOAD='(-0.01,0.01)';
      OUTPUT_LOAD='(1.0,-1.0)';
    'GPIOQ1||TACH1':
      PIN_NUMBER='(0,0,0,AB25,0,0)';
      BIDIRECTIONAL='TRUE';
      INPUT_LOAD='(-0.01,0.01)';
      OUTPUT_LOAD='(1.0,-1.0)';
    'GPIOQ2||TACH2':
      PIN_NUMBER='(0,0,0,Y24,0,0)';
      BIDIRECTIONAL='TRUE';
      INPUT_LOAD='(-0.01,0.01)';
      OUTPUT_LOAD='(1.0,-1.0)';
    'GPIOQ3||TACH3':
      PIN_NUMBER='(0,0,0,AB26,0,0)';
      BIDIRECTIONAL='TRUE';
      INPUT_LOAD='(-0.01,0.01)';
      OUTPUT_LOAD='(1.0,-1.0)';
    'GPIOQ4||TACH4':
      PIN_NUMBER='(0,0,0,Y26,0,0)';
      BIDIRECTIONAL='TRUE';
      INPUT_LOAD='(-0.01,0.01)';
      OUTPUT_LOAD='(1.0,-1.0)';
    'GPIOQ5||TACH5':
      PIN_NUMBER='(0,0,0,AC26,0,0)';
      BIDIRECTIONAL='TRUE';
      INPUT_LOAD='(-0.01,0.01)';
      OUTPUT_LOAD='(1.0,-1.0)';
    'GPIOQ6||TACH6':
      PIN_NUMBER='(0,0,0,Y25,0,0)';
      BIDIRECTIONAL='TRUE';
      INPUT_LOAD='(-0.01,0.01)';
      OUTPUT_LOAD='(1.0,-1.0)';
    'GPIOQ7||TACH7':
      PIN_NUMBER='(0,0,0,AA26,0,0)';
      BIDIRECTIONAL='TRUE';
      INPUT_LOAD='(-0.01,0.01)';
      OUTPUT_LOAD='(1.0,-1.0)';
    'GPIOR0||TACH8':
      PIN_NUMBER='(0,0,0,V25,0,0)';
      BIDIRECTIONAL='TRUE';
      INPUT_LOAD='(-0.01,0.01)';
      OUTPUT_LOAD='(1.0,-1.0)';
    'GPIOR1||TACH9':
      PIN_NUMBER='(0,0,0,U24,0,0)';
      BIDIRECTIONAL='TRUE';
      INPUT_LOAD='(-0.01,0.01)';
      OUTPUT_LOAD='(1.0,-1.0)';
    'GPIOR2||TACH10':
      PIN_NUMBER='(0,0,0,V24,0,0)';
      BIDIRECTIONAL='TRUE';
      INPUT_LOAD='(-0.01,0.01)';
      OUTPUT_LOAD='(1.0,-1.0)';
    'GPIOR3||TACH11':
      PIN_NUMBER='(0,0,0,V26,0,0)';
      BIDIRECTIONAL='TRUE';
      INPUT_LOAD='(-0.01,0.01)';
      OUTPUT_LOAD='(1.0,-1.0)';
    'GPIOR4||TACH12':
      PIN_NUMBER='(0,0,0,U25,0,0)';
      BIDIRECTIONAL='TRUE';
      INPUT_LOAD='(-0.01,0.01)';
      OUTPUT_LOAD='(1.0,-1.0)';
    'GPIOR5||TACH13':
      PIN_NUMBER='(0,0,0,T23,0,0)';
      BIDIRECTIONAL='TRUE';
      INPUT_LOAD='(-0.01,0.01)';
      OUTPUT_LOAD='(1.0,-1.0)';
    'GPIOR6||TACH14':
      PIN_NUMBER='(0,0,0,W26,0,0)';
      BIDIRECTIONAL='TRUE';
      INPUT_LOAD='(-0.01,0.01)';
      OUTPUT_LOAD='(1.0,-1.0)';
    'GPIOR7||TACH15':
      PIN_NUMBER='(0,0,0,U26,0,0)';
      BIDIRECTIONAL='TRUE';
      INPUT_LOAD='(-0.01,0.01)';
      OUTPUT_LOAD='(1.0,-1.0)';
    'GPIOP0||PWM8||THRUIN0':
      PIN_NUMBER='(0,0,0,AB22,0,0)';
      BIDIRECTIONAL='TRUE';
      INPUT_LOAD='(-0.01,0.01)';
      OUTPUT_LOAD='(1.0,-1.0)';
    'GPIOP1||PWM9||THRUOUT0':
      PIN_NUMBER='(0,0,0,W24,0,0)';
      BIDIRECTIONAL='TRUE';
      INPUT_LOAD='(-0.01,0.01)';
      OUTPUT_LOAD='(1.0,-1.0)';
    'GPIOP2||PWM10||THRUIN1':
      PIN_NUMBER='(0,0,0,AA23,0,0)';
      BIDIRECTIONAL='TRUE';
      INPUT_LOAD='(-0.01,0.01)';
      OUTPUT_LOAD='(1.0,-1.0)';
    'GPIOP3||PWM11||THRUOUT1':
      PIN_NUMBER='(0,0,0,AA24,0,0)';
      BIDIRECTIONAL='TRUE';
      INPUT_LOAD='(-0.01,0.01)';
      OUTPUT_LOAD='(1.0,-1.0)';
    'GPIOP4||PWM12||THRUIN2':
      PIN_NUMBER='(0,0,0,W23,0,0)';
      BIDIRECTIONAL='TRUE';
      INPUT_LOAD='(-0.01,0.01)';
      OUTPUT_LOAD='(1.0,-1.0)';
    'GPIOP5||PWM13||THRUOUT2':
      PIN_NUMBER='(0,0,0,AB23,0,0)';
      BIDIRECTIONAL='TRUE';
      INPUT_LOAD='(-0.01,0.01)';
      OUTPUT_LOAD='(1.0,-1.0)';
    'GPIOP6||PWM14':
      PIN_NUMBER='(0,0,0,AB24,0,0)';
      BIDIRECTIONAL='TRUE';
      INPUT_LOAD='(-0.01,0.01)';
      OUTPUT_LOAD='(1.0,-1.0)';
    'GPIOP7||PWM15||HBLED#':
      PIN_NUMBER='(0,0,0,Y23,0,0)';
      BIDIRECTIONAL='TRUE';
      INPUT_LOAD='(-0.01,0.01)';
      OUTPUT_LOAD='(1.0,-1.0)';
    'SSPRST#':
      PIN_NUMBER='(0,0,0,D7,0,0)';
      INPUT_LOAD='(-0.01,0.01)';
    'USB2AV18':
      PIN_NUMBER='(0,0,0,K10,0,0)';
      PINUSE='POWER';
      NO_LOAD_CHECK='Both';
      NO_IO_CHECK='Both';
      NO_ASSERT_CHECK='TRUE';
      NO_DIR_CHECK='TRUE';
      ALLOW_CONNECT='TRUE';
    'PECIVDD':
      PIN_NUMBER='(0,0,0,AA18,0,0)';
      PINUSE='POWER';
      NO_LOAD_CHECK='Both';
      NO_IO_CHECK='Both';
      NO_ASSERT_CHECK='TRUE';
      NO_DIR_CHECK='TRUE';
      ALLOW_CONNECT='TRUE';
    'PECI':
      PIN_NUMBER='(0,0,0,AF16,0,0)';
      BIDIRECTIONAL='TRUE';
      INPUT_LOAD='(-0.01,0.01)';
      OUTPUT_LOAD='(1.0,-1.0)';
    'GPIOI4||MTDO2':
      PIN_NUMBER='(0,0,0,C16,0,0)';
      BIDIRECTIONAL='TRUE';
      INPUT_LOAD='(-0.01,0.01)';
      OUTPUT_LOAD='(1.0,-1.0)';
    'GPIOI3||MTMS2||RXD13':
      PIN_NUMBER='(0,0,0,D16,0,0)';
      BIDIRECTIONAL='TRUE';
      INPUT_LOAD='(-0.01,0.01)';
      OUTPUT_LOAD='(1.0,-1.0)';
    'GPIOI2||MTCK2||TXD13':
      PIN_NUMBER='(0,0,0,E17,0,0)';
      BIDIRECTIONAL='TRUE';
      INPUT_LOAD='(-0.01,0.01)';
      OUTPUT_LOAD='(1.0,-1.0)';
    'GPIOI0||MNTRST2||TXD12':
      PIN_NUMBER='(0,0,0,D17,0,0)';
      BIDIRECTIONAL='TRUE';
      INPUT_LOAD='(-0.01,0.01)';
      OUTPUT_LOAD='(1.0,-1.0)';
    'GPIOI1||MTDI2||RXD12':
      PIN_NUMBER='(0,0,0,A16,0,0)';
      BIDIRECTIONAL='TRUE';
      INPUT_LOAD='(-0.01,0.01)';
      OUTPUT_LOAD='(1.0,-1.0)';
    'CHASI#':
      PIN_NUMBER='(0,0,0,AB21,0,0)';
      INPUT_LOAD='(-0.01,0.01)';
    'ADCREXT0':
      PIN_NUMBER='(0,0,0,0,AF20,0)';
      OUTPUT_LOAD='(1.0,-1.0)';
    'ADCVREFN0':
      PIN_NUMBER='(0,0,0,0,AB20,0)';
      OUTPUT_LOAD='(1.0,-1.0)';
    'ADCVREFP0':
      PIN_NUMBER='(0,0,0,0,AC20,0)';
      OUTPUT_LOAD='(1.0,-1.0)';
    'ADCAV33_Y21':
      PIN_NUMBER='(0,0,0,0,Y21,0)';
      PINUSE='POWER';
      NO_LOAD_CHECK='Both';
      NO_IO_CHECK='Both';
      NO_ASSERT_CHECK='TRUE';
      NO_DIR_CHECK='TRUE';
      ALLOW_CONNECT='TRUE';
    'DACAV33_V21':
      PIN_NUMBER='(0,0,0,0,V21,0)';
      PINUSE='POWER';
      NO_LOAD_CHECK='Both';
      NO_IO_CHECK='Both';
      NO_ASSERT_CHECK='TRUE';
      NO_DIR_CHECK='TRUE';
      ALLOW_CONNECT='TRUE';
    'DACRSET':
      PIN_NUMBER='(0,0,0,0,AC21,0)';
      BIDIRECTIONAL='TRUE';
      INPUT_LOAD='(-0.01,0.01)';
      OUTPUT_LOAD='(1.0,-1.0)';
    'PLLAVDD_E7':
      PIN_NUMBER='(0,0,0,0,E7,0)';
      PINUSE='POWER';
      NO_LOAD_CHECK='Both';
      NO_IO_CHECK='Both';
      NO_ASSERT_CHECK='TRUE';
      NO_DIR_CHECK='TRUE';
      ALLOW_CONNECT='TRUE';
    'PLLAHVDD':
      PIN_NUMBER='(0,0,0,0,H14,0)';
      PINUSE='POWER';
      NO_LOAD_CHECK='Both';
      NO_IO_CHECK='Both';
      NO_ASSERT_CHECK='TRUE';
      NO_DIR_CHECK='TRUE';
      ALLOW_CONNECT='TRUE';
    'ADCVREFP1':
      PIN_NUMBER='(0,0,0,0,AD17,0)';
      OUTPUT_LOAD='(1.0,-1.0)';
    'ADCVREFN1':
      PIN_NUMBER='(0,0,0,0,AD18,0)';
      OUTPUT_LOAD='(1.0,-1.0)';
    'ADCREXT1':
      PIN_NUMBER='(0,0,0,0,AF18,0)';
      OUTPUT_LOAD='(1.0,-1.0)';
    'IV10D_L9':
      PIN_NUMBER='(0,0,0,0,L9,0)';
      PINUSE='POWER';
      NO_LOAD_CHECK='Both';
      NO_IO_CHECK='Both';
      NO_ASSERT_CHECK='TRUE';
      NO_DIR_CHECK='TRUE';
      ALLOW_CONNECT='TRUE';
    'IV10D_L10':
      PIN_NUMBER='(0,0,0,0,L10,0)';
      PINUSE='POWER';
      NO_LOAD_CHECK='Both';
      NO_IO_CHECK='Both';
      NO_ASSERT_CHECK='TRUE';
      NO_DIR_CHECK='TRUE';
      ALLOW_CONNECT='TRUE';
    'IV10D_M8':
      PIN_NUMBER='(0,0,0,0,M8,0)';
      PINUSE='POWER';
      NO_LOAD_CHECK='Both';
      NO_IO_CHECK='Both';
      NO_ASSERT_CHECK='TRUE';
      NO_DIR_CHECK='TRUE';
      ALLOW_CONNECT='TRUE';
    'AVDDPLL':
      PIN_NUMBER='(0,0,0,0,N5,0)';
      PINUSE='POWER';
      NO_LOAD_CHECK='Both';
      NO_IO_CHECK='Both';
      NO_ASSERT_CHECK='TRUE';
      NO_DIR_CHECK='TRUE';
      ALLOW_CONNECT='TRUE';
    'MVDD_G6':
      PIN_NUMBER='(0,0,0,0,G6,0)';
      PINUSE='POWER';
      NO_LOAD_CHECK='Both';
      NO_IO_CHECK='Both';
      NO_ASSERT_CHECK='TRUE';
      NO_DIR_CHECK='TRUE';
      ALLOW_CONNECT='TRUE';
    'PLLAVDD_F7':
      PIN_NUMBER='(0,0,0,0,F7,0)';
      PINUSE='POWER';
      NO_LOAD_CHECK='Both';
      NO_IO_CHECK='Both';
      NO_ASSERT_CHECK='TRUE';
      NO_DIR_CHECK='TRUE';
      ALLOW_CONNECT='TRUE';
    'DACAV33_W21':
      PIN_NUMBER='(0,0,0,0,W21,0)';
      PINUSE='POWER';
      NO_LOAD_CHECK='Both';
      NO_IO_CHECK='Both';
      NO_ASSERT_CHECK='TRUE';
      NO_DIR_CHECK='TRUE';
      ALLOW_CONNECT='TRUE';
    'PLLDVDD_E9':
      PIN_NUMBER='(0,0,0,0,E9,0)';
      PINUSE='POWER';
      NO_LOAD_CHECK='Both';
      NO_IO_CHECK='Both';
      NO_ASSERT_CHECK='TRUE';
      NO_DIR_CHECK='TRUE';
      ALLOW_CONNECT='TRUE';
    'PLLDVDD_F9':
      PIN_NUMBER='(0,0,0,0,F9,0)';
      PINUSE='POWER';
      NO_LOAD_CHECK='Both';
      NO_IO_CHECK='Both';
      NO_ASSERT_CHECK='TRUE';
      NO_DIR_CHECK='TRUE';
      ALLOW_CONNECT='TRUE';
    'RC_VCC10A':
      PIN_NUMBER='(0,0,0,0,T9,0)';
      PINUSE='POWER';
      NO_LOAD_CHECK='Both';
      NO_IO_CHECK='Both';
      NO_ASSERT_CHECK='TRUE';
      NO_DIR_CHECK='TRUE';
      ALLOW_CONNECT='TRUE';
    'RC_VCC18A':
      PIN_NUMBER='(0,0,0,0,V9,0)';
      PINUSE='POWER';
      NO_LOAD_CHECK='Both';
      NO_IO_CHECK='Both';
      NO_ASSERT_CHECK='TRUE';
      NO_DIR_CHECK='TRUE';
      ALLOW_CONNECT='TRUE';
    'PE_VCC10A':
      PIN_NUMBER='(0,0,0,0,T10,0)';
      PINUSE='POWER';
      NO_LOAD_CHECK='Both';
      NO_IO_CHECK='Both';
      NO_ASSERT_CHECK='TRUE';
      NO_DIR_CHECK='TRUE';
      ALLOW_CONNECT='TRUE';
    'PE_VCC18A':
      PIN_NUMBER='(0,0,0,0,V10,0)';
      PINUSE='POWER';
      NO_LOAD_CHECK='Both';
      NO_IO_CHECK='Both';
      NO_ASSERT_CHECK='TRUE';
      NO_DIR_CHECK='TRUE';
      ALLOW_CONNECT='TRUE';
    'DP_VCC18A':
      PIN_NUMBER='(0,0,0,0,V8,0)';
      PINUSE='POWER';
      NO_LOAD_CHECK='Both';
      NO_IO_CHECK='Both';
      NO_ASSERT_CHECK='TRUE';
      NO_DIR_CHECK='TRUE';
      ALLOW_CONNECT='TRUE';
    'DP_VCC10A':
      PIN_NUMBER='(0,0,0,0,T8,0)';
      PINUSE='POWER';
      NO_LOAD_CHECK='Both';
      NO_IO_CHECK='Both';
      NO_ASSERT_CHECK='TRUE';
      NO_DIR_CHECK='TRUE';
      ALLOW_CONNECT='TRUE';
    'MVDD_H6':
      PIN_NUMBER='(0,0,0,0,H6,0)';
      PINUSE='POWER';
      NO_LOAD_CHECK='Both';
      NO_IO_CHECK='Both';
      NO_ASSERT_CHECK='TRUE';
      NO_DIR_CHECK='TRUE';
      ALLOW_CONNECT='TRUE';
    'MVDD_J6':
      PIN_NUMBER='(0,0,0,0,J6,0)';
      PINUSE='POWER';
      NO_LOAD_CHECK='Both';
      NO_IO_CHECK='Both';
      NO_ASSERT_CHECK='TRUE';
      NO_DIR_CHECK='TRUE';
      ALLOW_CONNECT='TRUE';
    'MVDD_K6':
      PIN_NUMBER='(0,0,0,0,K6,0)';
      PINUSE='POWER';
      NO_LOAD_CHECK='Both';
      NO_IO_CHECK='Both';
      NO_ASSERT_CHECK='TRUE';
      NO_DIR_CHECK='TRUE';
      ALLOW_CONNECT='TRUE';
    'MVDD_L6':
      PIN_NUMBER='(0,0,0,0,L6,0)';
      PINUSE='POWER';
      NO_LOAD_CHECK='Both';
      NO_IO_CHECK='Both';
      NO_ASSERT_CHECK='TRUE';
      NO_DIR_CHECK='TRUE';
      ALLOW_CONNECT='TRUE';
    'MVDD_P6':
      PIN_NUMBER='(0,0,0,0,P6,0)';
      PINUSE='POWER';
      NO_LOAD_CHECK='Both';
      NO_IO_CHECK='Both';
      NO_ASSERT_CHECK='TRUE';
      NO_DIR_CHECK='TRUE';
      ALLOW_CONNECT='TRUE';
    'MVDD_R6':
      PIN_NUMBER='(0,0,0,0,R6,0)';
      PINUSE='POWER';
      NO_LOAD_CHECK='Both';
      NO_IO_CHECK='Both';
      NO_ASSERT_CHECK='TRUE';
      NO_DIR_CHECK='TRUE';
      ALLOW_CONNECT='TRUE';
    'MVDD_T6':
      PIN_NUMBER='(0,0,0,0,T6,0)';
      PINUSE='POWER';
      NO_LOAD_CHECK='Both';
      NO_IO_CHECK='Both';
      NO_ASSERT_CHECK='TRUE';
      NO_DIR_CHECK='TRUE';
      ALLOW_CONNECT='TRUE';
    'MVDD_CK':
      PIN_NUMBER='(0,0,0,0,M6,0)';
      PINUSE='POWER';
      NO_LOAD_CHECK='Both';
      NO_IO_CHECK='Both';
      NO_ASSERT_CHECK='TRUE';
      NO_DIR_CHECK='TRUE';
      ALLOW_CONNECT='TRUE';
    'IV12D_K16':
      PIN_NUMBER='(0,0,0,0,K16,0)';
      PINUSE='POWER';
      NO_LOAD_CHECK='Both';
      NO_IO_CHECK='Both';
      NO_ASSERT_CHECK='TRUE';
      NO_DIR_CHECK='TRUE';
      ALLOW_CONNECT='TRUE';
    'IV12D_K17':
      PIN_NUMBER='(0,0,0,0,K17,0)';
      PINUSE='POWER';
      NO_LOAD_CHECK='Both';
      NO_IO_CHECK='Both';
      NO_ASSERT_CHECK='TRUE';
      NO_DIR_CHECK='TRUE';
      ALLOW_CONNECT='TRUE';
    'IV12D_K18':
      PIN_NUMBER='(0,0,0,0,K18,0)';
      PINUSE='POWER';
      NO_LOAD_CHECK='Both';
      NO_IO_CHECK='Both';
      NO_ASSERT_CHECK='TRUE';
      NO_DIR_CHECK='TRUE';
      ALLOW_CONNECT='TRUE';
    'IV12D_K19':
      PIN_NUMBER='(0,0,0,0,K19,0)';
      PINUSE='POWER';
      NO_LOAD_CHECK='Both';
      NO_IO_CHECK='Both';
      NO_ASSERT_CHECK='TRUE';
      NO_DIR_CHECK='TRUE';
      ALLOW_CONNECT='TRUE';
    'IV12D_L14':
      PIN_NUMBER='(0,0,0,0,L14,0)';
      PINUSE='POWER';
      NO_LOAD_CHECK='Both';
      NO_IO_CHECK='Both';
      NO_ASSERT_CHECK='TRUE';
      NO_DIR_CHECK='TRUE';
      ALLOW_CONNECT='TRUE';
    'IV12D_M14':
      PIN_NUMBER='(0,0,0,0,M14,0)';
      PINUSE='POWER';
      NO_LOAD_CHECK='Both';
      NO_IO_CHECK='Both';
      NO_ASSERT_CHECK='TRUE';
      NO_DIR_CHECK='TRUE';
      ALLOW_CONNECT='TRUE';
    'IV12D_N14':
      PIN_NUMBER='(0,0,0,0,N14,0)';
      PINUSE='POWER';
      NO_LOAD_CHECK='Both';
      NO_IO_CHECK='Both';
      NO_ASSERT_CHECK='TRUE';
      NO_DIR_CHECK='TRUE';
      ALLOW_CONNECT='TRUE';
    'IV12D_P14':
      PIN_NUMBER='(0,0,0,0,P14,0)';
      PINUSE='POWER';
      NO_LOAD_CHECK='Both';
      NO_IO_CHECK='Both';
      NO_ASSERT_CHECK='TRUE';
      NO_DIR_CHECK='TRUE';
      ALLOW_CONNECT='TRUE';
    'IV12D_R14':
      PIN_NUMBER='(0,0,0,0,R14,0)';
      PINUSE='POWER';
      NO_LOAD_CHECK='Both';
      NO_IO_CHECK='Both';
      NO_ASSERT_CHECK='TRUE';
      NO_DIR_CHECK='TRUE';
      ALLOW_CONNECT='TRUE';
    'IV12D_T14':
      PIN_NUMBER='(0,0,0,0,T14,0)';
      PINUSE='POWER';
      NO_LOAD_CHECK='Both';
      NO_IO_CHECK='Both';
      NO_ASSERT_CHECK='TRUE';
      NO_DIR_CHECK='TRUE';
      ALLOW_CONNECT='TRUE';
    'IV12D_L21':
      PIN_NUMBER='(0,0,0,0,L21,0)';
      PINUSE='POWER';
      NO_LOAD_CHECK='Both';
      NO_IO_CHECK='Both';
      NO_ASSERT_CHECK='TRUE';
      NO_DIR_CHECK='TRUE';
      ALLOW_CONNECT='TRUE';
    'IV12D_M21':
      PIN_NUMBER='(0,0,0,0,M21,0)';
      PINUSE='POWER';
      NO_LOAD_CHECK='Both';
      NO_IO_CHECK='Both';
      NO_ASSERT_CHECK='TRUE';
      NO_DIR_CHECK='TRUE';
      ALLOW_CONNECT='TRUE';
    'IV12D_N21':
      PIN_NUMBER='(0,0,0,0,N21,0)';
      PINUSE='POWER';
      NO_LOAD_CHECK='Both';
      NO_IO_CHECK='Both';
      NO_ASSERT_CHECK='TRUE';
      NO_DIR_CHECK='TRUE';
      ALLOW_CONNECT='TRUE';
    'IV12D_P21':
      PIN_NUMBER='(0,0,0,0,P21,0)';
      PINUSE='POWER';
      NO_LOAD_CHECK='Both';
      NO_IO_CHECK='Both';
      NO_ASSERT_CHECK='TRUE';
      NO_DIR_CHECK='TRUE';
      ALLOW_CONNECT='TRUE';
    'IV12D_R21':
      PIN_NUMBER='(0,0,0,0,R21,0)';
      PINUSE='POWER';
      NO_LOAD_CHECK='Both';
      NO_IO_CHECK='Both';
      NO_ASSERT_CHECK='TRUE';
      NO_DIR_CHECK='TRUE';
      ALLOW_CONNECT='TRUE';
    'IV12D_T21':
      PIN_NUMBER='(0,0,0,0,T21,0)';
      PINUSE='POWER';
      NO_LOAD_CHECK='Both';
      NO_IO_CHECK='Both';
      NO_ASSERT_CHECK='TRUE';
      NO_DIR_CHECK='TRUE';
      ALLOW_CONNECT='TRUE';
    'IV12D_U15':
      PIN_NUMBER='(0,0,0,0,U15,0)';
      PINUSE='POWER';
      NO_LOAD_CHECK='Both';
      NO_IO_CHECK='Both';
      NO_ASSERT_CHECK='TRUE';
      NO_DIR_CHECK='TRUE';
      ALLOW_CONNECT='TRUE';
    'IV12D_U16':
      PIN_NUMBER='(0,0,0,0,U16,0)';
      PINUSE='POWER';
      NO_LOAD_CHECK='Both';
      NO_IO_CHECK='Both';
      NO_ASSERT_CHECK='TRUE';
      NO_DIR_CHECK='TRUE';
      ALLOW_CONNECT='TRUE';
    'IV12D_U17':
      PIN_NUMBER='(0,0,0,0,U17,0)';
      PINUSE='POWER';
      NO_LOAD_CHECK='Both';
      NO_IO_CHECK='Both';
      NO_ASSERT_CHECK='TRUE';
      NO_DIR_CHECK='TRUE';
      ALLOW_CONNECT='TRUE';
    'IV12D_U18':
      PIN_NUMBER='(0,0,0,0,U18,0)';
      PINUSE='POWER';
      NO_LOAD_CHECK='Both';
      NO_IO_CHECK='Both';
      NO_ASSERT_CHECK='TRUE';
      NO_DIR_CHECK='TRUE';
      ALLOW_CONNECT='TRUE';
    'RVDD_L22':
      PIN_NUMBER='(0,0,0,0,L22,0)';
      PINUSE='POWER';
      NO_LOAD_CHECK='Both';
      NO_IO_CHECK='Both';
      NO_ASSERT_CHECK='TRUE';
      NO_DIR_CHECK='TRUE';
      ALLOW_CONNECT='TRUE';
    'RVDD_M22':
      PIN_NUMBER='(0,0,0,0,M22,0)';
      PINUSE='POWER';
      NO_LOAD_CHECK='Both';
      NO_IO_CHECK='Both';
      NO_ASSERT_CHECK='TRUE';
      NO_DIR_CHECK='TRUE';
      ALLOW_CONNECT='TRUE';
    'RVDD_J21':
      PIN_NUMBER='(0,0,0,0,J21,0)';
      PINUSE='POWER';
      NO_LOAD_CHECK='Both';
      NO_IO_CHECK='Both';
      NO_ASSERT_CHECK='TRUE';
      NO_DIR_CHECK='TRUE';
      ALLOW_CONNECT='TRUE';
    'RVDD_K21':
      PIN_NUMBER='(0,0,0,0,K21,0)';
      PINUSE='POWER';
      NO_LOAD_CHECK='Both';
      NO_IO_CHECK='Both';
      NO_ASSERT_CHECK='TRUE';
      NO_DIR_CHECK='TRUE';
      ALLOW_CONNECT='TRUE';
    'SD1VDD_G21':
      PIN_NUMBER='(0,0,0,0,G21,0)';
      PINUSE='POWER';
      NO_LOAD_CHECK='Both';
      NO_IO_CHECK='Both';
      NO_ASSERT_CHECK='TRUE';
      NO_DIR_CHECK='TRUE';
      ALLOW_CONNECT='TRUE';
    'SD2VDD_H18':
      PIN_NUMBER='(0,0,0,0,H18,0)';
      PINUSE='POWER';
      NO_LOAD_CHECK='Both';
      NO_IO_CHECK='Both';
      NO_ASSERT_CHECK='TRUE';
      NO_DIR_CHECK='TRUE';
      ALLOW_CONNECT='TRUE';
    'LPVDD':
      PIN_NUMBER='(0,0,0,0,W15,0)';
      PINUSE='POWER';
      NO_LOAD_CHECK='Both';
      NO_IO_CHECK='Both';
      NO_ASSERT_CHECK='TRUE';
      NO_DIR_CHECK='TRUE';
      ALLOW_CONNECT='TRUE';
    'I3CVDDH_F19':
      PIN_NUMBER='(0,0,0,0,F19,0)';
      PINUSE='POWER';
      NO_LOAD_CHECK='Both';
      NO_IO_CHECK='Both';
      NO_ASSERT_CHECK='TRUE';
      NO_DIR_CHECK='TRUE';
      ALLOW_CONNECT='TRUE';
    'IV10D_N8':
      PIN_NUMBER='(0,0,0,0,N8,0)';
      PINUSE='POWER';
      NO_LOAD_CHECK='Both';
      NO_IO_CHECK='Both';
      NO_ASSERT_CHECK='TRUE';
      NO_DIR_CHECK='TRUE';
      ALLOW_CONNECT='TRUE';
    'IV10D_P8':
      PIN_NUMBER='(0,0,0,0,P8,0)';
      PINUSE='POWER';
      NO_LOAD_CHECK='Both';
      NO_IO_CHECK='Both';
      NO_ASSERT_CHECK='TRUE';
      NO_DIR_CHECK='TRUE';
      ALLOW_CONNECT='TRUE';
    'IV10D_M11':
      PIN_NUMBER='(0,0,0,0,M11,0)';
      PINUSE='POWER';
      NO_LOAD_CHECK='Both';
      NO_IO_CHECK='Both';
      NO_ASSERT_CHECK='TRUE';
      NO_DIR_CHECK='TRUE';
      ALLOW_CONNECT='TRUE';
    'IV10D_N11':
      PIN_NUMBER='(0,0,0,0,N11,0)';
      PINUSE='POWER';
      NO_LOAD_CHECK='Both';
      NO_IO_CHECK='Both';
      NO_ASSERT_CHECK='TRUE';
      NO_DIR_CHECK='TRUE';
      ALLOW_CONNECT='TRUE';
    'IV10D_P11':
      PIN_NUMBER='(0,0,0,0,P11,0)';
      PINUSE='POWER';
      NO_LOAD_CHECK='Both';
      NO_IO_CHECK='Both';
      NO_ASSERT_CHECK='TRUE';
      NO_DIR_CHECK='TRUE';
      ALLOW_CONNECT='TRUE';
    'IV10D_R9':
      PIN_NUMBER='(0,0,0,0,R9,0)';
      PINUSE='POWER';
      NO_LOAD_CHECK='Both';
      NO_IO_CHECK='Both';
      NO_ASSERT_CHECK='TRUE';
      NO_DIR_CHECK='TRUE';
      ALLOW_CONNECT='TRUE';
    'PV18D_U6':
      PIN_NUMBER='(0,0,0,0,U6,0)';
      PINUSE='POWER';
      NO_LOAD_CHECK='Both';
      NO_IO_CHECK='Both';
      NO_ASSERT_CHECK='TRUE';
      NO_DIR_CHECK='TRUE';
      ALLOW_CONNECT='TRUE';
    'PV18D_V6':
      PIN_NUMBER='(0,0,0,0,V6,0)';
      PINUSE='POWER';
      NO_LOAD_CHECK='Both';
      NO_IO_CHECK='Both';
      NO_ASSERT_CHECK='TRUE';
      NO_DIR_CHECK='TRUE';
      ALLOW_CONNECT='TRUE';
    'PV18D_H8':
      PIN_NUMBER='(0,0,0,0,H8,0)';
      PINUSE='POWER';
      NO_LOAD_CHECK='Both';
      NO_IO_CHECK='Both';
      NO_ASSERT_CHECK='TRUE';
      NO_DIR_CHECK='TRUE';
      ALLOW_CONNECT='TRUE';
    'PV18D_J8':
      PIN_NUMBER='(0,0,0,0,J8,0)';
      PINUSE='POWER';
      NO_LOAD_CHECK='Both';
      NO_IO_CHECK='Both';
      NO_ASSERT_CHECK='TRUE';
      NO_DIR_CHECK='TRUE';
      ALLOW_CONNECT='TRUE';
    'PV18D_RGM_H12':
      PIN_NUMBER='(0,0,0,0,H12,0)';
      PINUSE='POWER';
      NO_LOAD_CHECK='Both';
      NO_IO_CHECK='Both';
      NO_ASSERT_CHECK='TRUE';
      NO_DIR_CHECK='TRUE';
      ALLOW_CONNECT='TRUE';
    'PV33D_H16':
      PIN_NUMBER='(0,0,0,0,H16,0)';
      PINUSE='POWER';
      NO_LOAD_CHECK='Both';
      NO_IO_CHECK='Both';
      NO_ASSERT_CHECK='TRUE';
      NO_DIR_CHECK='TRUE';
      ALLOW_CONNECT='TRUE';
    'PV33D_H17':
      PIN_NUMBER='(0,0,0,0,H17,0)';
      PINUSE='POWER';
      NO_LOAD_CHECK='Both';
      NO_IO_CHECK='Both';
      NO_ASSERT_CHECK='TRUE';
      NO_DIR_CHECK='TRUE';
      ALLOW_CONNECT='TRUE';
    'PV33D_W16':
      PIN_NUMBER='(0,0,0,0,W16,0)';
      PINUSE='POWER';
      NO_LOAD_CHECK='Both';
      NO_IO_CHECK='Both';
      NO_ASSERT_CHECK='TRUE';
      NO_DIR_CHECK='TRUE';
      ALLOW_CONNECT='TRUE';
    'PV33D_W17':
      PIN_NUMBER='(0,0,0,0,W17,0)';
      PINUSE='POWER';
      NO_LOAD_CHECK='Both';
      NO_IO_CHECK='Both';
      NO_ASSERT_CHECK='TRUE';
      NO_DIR_CHECK='TRUE';
      ALLOW_CONNECT='TRUE';
    'PV33D_W18':
      PIN_NUMBER='(0,0,0,0,W18,0)';
      PINUSE='POWER';
      NO_LOAD_CHECK='Both';
      NO_IO_CHECK='Both';
      NO_ASSERT_CHECK='TRUE';
      NO_DIR_CHECK='TRUE';
      ALLOW_CONNECT='TRUE';
    'PV33D_W19':
      PIN_NUMBER='(0,0,0,0,W19,0)';
      PINUSE='POWER';
      NO_LOAD_CHECK='Both';
      NO_IO_CHECK='Both';
      NO_ASSERT_CHECK='TRUE';
      NO_DIR_CHECK='TRUE';
      ALLOW_CONNECT='TRUE';
    'PV33D_N22':
      PIN_NUMBER='(0,0,0,0,N22,0)';
      PINUSE='POWER';
      NO_LOAD_CHECK='Both';
      NO_IO_CHECK='Both';
      NO_ASSERT_CHECK='TRUE';
      NO_DIR_CHECK='TRUE';
      ALLOW_CONNECT='TRUE';
    'PV33D_P22':
      PIN_NUMBER='(0,0,0,0,P22,0)';
      PINUSE='POWER';
      NO_LOAD_CHECK='Both';
      NO_IO_CHECK='Both';
      NO_ASSERT_CHECK='TRUE';
      NO_DIR_CHECK='TRUE';
      ALLOW_CONNECT='TRUE';
    'PV33D_R22':
      PIN_NUMBER='(0,0,0,0,R22,0)';
      PINUSE='POWER';
      NO_LOAD_CHECK='Both';
      NO_IO_CHECK='Both';
      NO_ASSERT_CHECK='TRUE';
      NO_DIR_CHECK='TRUE';
      ALLOW_CONNECT='TRUE';
    'PV33D_T22':
      PIN_NUMBER='(0,0,0,0,T22,0)';
      PINUSE='POWER';
      NO_LOAD_CHECK='Both';
      NO_IO_CHECK='Both';
      NO_ASSERT_CHECK='TRUE';
      NO_DIR_CHECK='TRUE';
      ALLOW_CONNECT='TRUE';
    'BATVDD':
      PIN_NUMBER='(0,0,0,0,V23,0)';
      PINUSE='POWER';
      NO_LOAD_CHECK='Both';
      NO_IO_CHECK='Both';
      NO_ASSERT_CHECK='TRUE';
      NO_DIR_CHECK='TRUE';
      ALLOW_CONNECT='TRUE';
    'PV18D_SLI_L13':
      PIN_NUMBER='(0,0,0,0,L13,0)';
      PINUSE='POWER';
      NO_LOAD_CHECK='Both';
      NO_IO_CHECK='Both';
      NO_ASSERT_CHECK='TRUE';
      NO_DIR_CHECK='TRUE';
      ALLOW_CONNECT='TRUE';
    'PV18D_SLI_M13':
      PIN_NUMBER='(0,0,0,0,M13,0)';
      PINUSE='POWER';
      NO_LOAD_CHECK='Both';
      NO_IO_CHECK='Both';
      NO_ASSERT_CHECK='TRUE';
      NO_DIR_CHECK='TRUE';
      ALLOW_CONNECT='TRUE';
    'PV18D_SLI_N13':
      PIN_NUMBER='(0,0,0,0,N13,0)';
      PINUSE='POWER';
      NO_LOAD_CHECK='Both';
      NO_IO_CHECK='Both';
      NO_ASSERT_CHECK='TRUE';
      NO_DIR_CHECK='TRUE';
      ALLOW_CONNECT='TRUE';
    'PV18D_SLI_P13':
      PIN_NUMBER='(0,0,0,0,P13,0)';
      PINUSE='POWER';
      NO_LOAD_CHECK='Both';
      NO_IO_CHECK='Both';
      NO_ASSERT_CHECK='TRUE';
      NO_DIR_CHECK='TRUE';
      ALLOW_CONNECT='TRUE';
    'PV18D_SLI_R13':
      PIN_NUMBER='(0,0,0,0,R13,0)';
      PINUSE='POWER';
      NO_LOAD_CHECK='Both';
      NO_IO_CHECK='Both';
      NO_ASSERT_CHECK='TRUE';
      NO_DIR_CHECK='TRUE';
      ALLOW_CONNECT='TRUE';
    'PV18D_SLI_T13':
      PIN_NUMBER='(0,0,0,0,T13,0)';
      PINUSE='POWER';
      NO_LOAD_CHECK='Both';
      NO_IO_CHECK='Both';
      NO_ASSERT_CHECK='TRUE';
      NO_DIR_CHECK='TRUE';
      ALLOW_CONNECT='TRUE';
    'PV18D_SLI_U13':
      PIN_NUMBER='(0,0,0,0,U13,0)';
      PINUSE='POWER';
      NO_LOAD_CHECK='Both';
      NO_IO_CHECK='Both';
      NO_ASSERT_CHECK='TRUE';
      NO_DIR_CHECK='TRUE';
      ALLOW_CONNECT='TRUE';
    'PV18D_SLI_V13':
      PIN_NUMBER='(0,0,0,0,V13,0)';
      PINUSE='POWER';
      NO_LOAD_CHECK='Both';
      NO_IO_CHECK='Both';
      NO_ASSERT_CHECK='TRUE';
      NO_DIR_CHECK='TRUE';
      ALLOW_CONNECT='TRUE';
    'PV18D_SLI_W13':
      PIN_NUMBER='(0,0,0,0,W13,0)';
      PINUSE='POWER';
      NO_LOAD_CHECK='Both';
      NO_IO_CHECK='Both';
      NO_ASSERT_CHECK='TRUE';
      NO_DIR_CHECK='TRUE';
      ALLOW_CONNECT='TRUE';
    'PV18D_SLI_W14':
      PIN_NUMBER='(0,0,0,0,W14,0)';
      PINUSE='POWER';
      NO_LOAD_CHECK='Both';
      NO_IO_CHECK='Both';
      NO_ASSERT_CHECK='TRUE';
      NO_DIR_CHECK='TRUE';
      ALLOW_CONNECT='TRUE';
    'ADCAV33_AA21':
      PIN_NUMBER='(0,0,0,0,AA21,0)';
      PINUSE='POWER';
      NO_LOAD_CHECK='Both';
      NO_IO_CHECK='Both';
      NO_ASSERT_CHECK='TRUE';
      NO_DIR_CHECK='TRUE';
      ALLOW_CONNECT='TRUE';
    'PV18D_RGM_J12':
      PIN_NUMBER='(0,0,0,0,J12,0)';
      PINUSE='POWER';
      NO_LOAD_CHECK='Both';
      NO_IO_CHECK='Both';
      NO_ASSERT_CHECK='TRUE';
      NO_DIR_CHECK='TRUE';
      ALLOW_CONNECT='TRUE';
    'IV10D_R10':
      PIN_NUMBER='(0,0,0,0,R10,0)';
      PINUSE='POWER';
      NO_LOAD_CHECK='Both';
      NO_IO_CHECK='Both';
      NO_ASSERT_CHECK='TRUE';
      NO_DIR_CHECK='TRUE';
      ALLOW_CONNECT='TRUE';
    'ADCVREFEXT0':
      PIN_NUMBER='(0,0,0,0,AF19,0)';
      PINUSE='POWER';
      NO_LOAD_CHECK='Both';
      NO_IO_CHECK='Both';
      NO_ASSERT_CHECK='TRUE';
      NO_DIR_CHECK='TRUE';
      ALLOW_CONNECT='TRUE';
    'ADCVREFEXT1':
      PIN_NUMBER='(0,0,0,0,AF17,0)';
      PINUSE='POWER';
      NO_LOAD_CHECK='Both';
      NO_IO_CHECK='Both';
      NO_ASSERT_CHECK='TRUE';
      NO_DIR_CHECK='TRUE';
      ALLOW_CONNECT='TRUE';
    'PV18D_N12':
      PIN_NUMBER='(0,0,0,0,N12,0)';
      PINUSE='POWER';
      NO_LOAD_CHECK='Both';
      NO_IO_CHECK='Both';
      NO_ASSERT_CHECK='TRUE';
      NO_DIR_CHECK='TRUE';
      ALLOW_CONNECT='TRUE';
    'PV18D_P12':
      PIN_NUMBER='(0,0,0,0,P12,0)';
      PINUSE='POWER';
      NO_LOAD_CHECK='Both';
      NO_IO_CHECK='Both';
      NO_ASSERT_CHECK='TRUE';
      NO_DIR_CHECK='TRUE';
      ALLOW_CONNECT='TRUE';
    'PV18D_R12':
      PIN_NUMBER='(0,0,0,0,R12,0)';
      PINUSE='POWER';
      NO_LOAD_CHECK='Both';
      NO_IO_CHECK='Both';
      NO_ASSERT_CHECK='TRUE';
      NO_DIR_CHECK='TRUE';
      ALLOW_CONNECT='TRUE';
    'SD1VDD_H21':
      PIN_NUMBER='(0,0,0,0,H21,0)';
      PINUSE='POWER';
      NO_LOAD_CHECK='Both';
      NO_IO_CHECK='Both';
      NO_ASSERT_CHECK='TRUE';
      NO_DIR_CHECK='TRUE';
      ALLOW_CONNECT='TRUE';
    'SD2VDD_H19':
      PIN_NUMBER='(0,0,0,0,H19,0)';
      PINUSE='POWER';
      NO_LOAD_CHECK='Both';
      NO_IO_CHECK='Both';
      NO_ASSERT_CHECK='TRUE';
      NO_DIR_CHECK='TRUE';
      ALLOW_CONNECT='TRUE';
    'I3CVDDH_F20':
      PIN_NUMBER='(0,0,0,0,F20,0)';
      PINUSE='POWER';
      NO_LOAD_CHECK='Both';
      NO_IO_CHECK='Both';
      NO_ASSERT_CHECK='TRUE';
      NO_DIR_CHECK='TRUE';
      ALLOW_CONNECT='TRUE';
    'PV33D_H15':
      PIN_NUMBER='(0,0,0,0,H15,0)';
      PINUSE='POWER';
      NO_LOAD_CHECK='Both';
      NO_IO_CHECK='Both';
      NO_ASSERT_CHECK='TRUE';
      NO_DIR_CHECK='TRUE';
      ALLOW_CONNECT='TRUE';
    'DPLLAVDD':
      PIN_NUMBER='(0,0,0,0,J9,0)';
      PINUSE='POWER';
      NO_LOAD_CHECK='Both';
      NO_IO_CHECK='Both';
      NO_ASSERT_CHECK='TRUE';
      NO_DIR_CHECK='TRUE';
      ALLOW_CONNECT='TRUE';
    'I3CVDDL1':
      PIN_NUMBER='(0,0,0,0,V22,0)';
      PINUSE='POWER';
      NO_LOAD_CHECK='Both';
      NO_IO_CHECK='Both';
      NO_ASSERT_CHECK='TRUE';
      NO_DIR_CHECK='TRUE';
      ALLOW_CONNECT='TRUE';
    'I3CVDDL2':
      PIN_NUMBER='(0,0,0,0,U21,0)';
      PINUSE='POWER';
      NO_LOAD_CHECK='Both';
      NO_IO_CHECK='Both';
      NO_ASSERT_CHECK='TRUE';
      NO_DIR_CHECK='TRUE';
      ALLOW_CONNECT='TRUE';
    'PV33D_RGM_K11':
      PIN_NUMBER='(0,0,0,0,K11,0)';
      PINUSE='POWER';
      NO_LOAD_CHECK='Both';
      NO_IO_CHECK='Both';
      NO_ASSERT_CHECK='TRUE';
      NO_DIR_CHECK='TRUE';
      ALLOW_CONNECT='TRUE';
    'PV33D_RGM_K12':
      PIN_NUMBER='(0,0,0,0,K12,0)';
      PINUSE='POWER';
      NO_LOAD_CHECK='Both';
      NO_IO_CHECK='Both';
      NO_ASSERT_CHECK='TRUE';
      NO_DIR_CHECK='TRUE';
      ALLOW_CONNECT='TRUE';
    'GND_A1':
      PIN_NUMBER='(0,0,0,0,0,A1)';
      PINUSE='POWER';
      NO_LOAD_CHECK='Both';
      NO_IO_CHECK='Both';
      NO_ASSERT_CHECK='TRUE';
      NO_DIR_CHECK='TRUE';
      ALLOW_CONNECT='TRUE';
    'GND_A5':
      PIN_NUMBER='(0,0,0,0,0,A5)';
      PINUSE='POWER';
      NO_LOAD_CHECK='Both';
      NO_IO_CHECK='Both';
      NO_ASSERT_CHECK='TRUE';
      NO_DIR_CHECK='TRUE';
      ALLOW_CONNECT='TRUE';
    'GND_A26':
      PIN_NUMBER='(0,0,0,0,0,A26)';
      PINUSE='POWER';
      NO_LOAD_CHECK='Both';
      NO_IO_CHECK='Both';
      NO_ASSERT_CHECK='TRUE';
      NO_DIR_CHECK='TRUE';
      ALLOW_CONNECT='TRUE';
    'GND_B5':
      PIN_NUMBER='(0,0,0,0,0,B5)';
      PINUSE='POWER';
      NO_LOAD_CHECK='Both';
      NO_IO_CHECK='Both';
      NO_ASSERT_CHECK='TRUE';
      NO_DIR_CHECK='TRUE';
      ALLOW_CONNECT='TRUE';
    'GND_B11':
      PIN_NUMBER='(0,0,0,0,0,B11)';
      PINUSE='POWER';
      NO_LOAD_CHECK='Both';
      NO_IO_CHECK='Both';
      NO_ASSERT_CHECK='TRUE';
      NO_DIR_CHECK='TRUE';
      ALLOW_CONNECT='TRUE';
    'GND_B15':
      PIN_NUMBER='(0,0,0,0,0,B15)';
      PINUSE='POWER';
      NO_LOAD_CHECK='Both';
      NO_IO_CHECK='Both';
      NO_ASSERT_CHECK='TRUE';
      NO_DIR_CHECK='TRUE';
      ALLOW_CONNECT='TRUE';
    'GND_B19':
      PIN_NUMBER='(0,0,0,0,0,B19)';
      PINUSE='POWER';
      NO_LOAD_CHECK='Both';
      NO_IO_CHECK='Both';
      NO_ASSERT_CHECK='TRUE';
      NO_DIR_CHECK='TRUE';
      ALLOW_CONNECT='TRUE';
    'GND_B23':
      PIN_NUMBER='(0,0,0,0,0,B23)';
      PINUSE='POWER';
      NO_LOAD_CHECK='Both';
      NO_IO_CHECK='Both';
      NO_ASSERT_CHECK='TRUE';
      NO_DIR_CHECK='TRUE';
      ALLOW_CONNECT='TRUE';
    'GND_C3':
      PIN_NUMBER='(0,0,0,0,0,C3)';
      PINUSE='POWER';
      NO_LOAD_CHECK='Both';
      NO_IO_CHECK='Both';
      NO_ASSERT_CHECK='TRUE';
      NO_DIR_CHECK='TRUE';
      ALLOW_CONNECT='TRUE';
    'GND_D25':
      PIN_NUMBER='(0,0,0,0,0,D25)';
      PINUSE='POWER';
      NO_LOAD_CHECK='Both';
      NO_IO_CHECK='Both';
      NO_ASSERT_CHECK='TRUE';
      NO_DIR_CHECK='TRUE';
      ALLOW_CONNECT='TRUE';
    'GND_E8':
      PIN_NUMBER='(0,0,0,0,0,E8)';
      PINUSE='POWER';
      NO_LOAD_CHECK='Both';
      NO_IO_CHECK='Both';
      NO_ASSERT_CHECK='TRUE';
      NO_DIR_CHECK='TRUE';
      ALLOW_CONNECT='TRUE';
    'GND_F6':
      PIN_NUMBER='(0,0,0,0,0,F6)';
      PINUSE='POWER';
      NO_LOAD_CHECK='Both';
      NO_IO_CHECK='Both';
      NO_ASSERT_CHECK='TRUE';
      NO_DIR_CHECK='TRUE';
      ALLOW_CONNECT='TRUE';
    'GND_F8':
      PIN_NUMBER='(0,0,0,0,0,F8)';
      PINUSE='POWER';
      NO_LOAD_CHECK='Both';
      NO_IO_CHECK='Both';
      NO_ASSERT_CHECK='TRUE';
      NO_DIR_CHECK='TRUE';
      ALLOW_CONNECT='TRUE';
    'GND_F10':
      PIN_NUMBER='(0,0,0,0,0,F10)';
      PINUSE='POWER';
      NO_LOAD_CHECK='Both';
      NO_IO_CHECK='Both';
      NO_ASSERT_CHECK='TRUE';
      NO_DIR_CHECK='TRUE';
      ALLOW_CONNECT='TRUE';
    'GND_F12':
      PIN_NUMBER='(0,0,0,0,0,F12)';
      PINUSE='POWER';
      NO_LOAD_CHECK='Both';
      NO_IO_CHECK='Both';
      NO_ASSERT_CHECK='TRUE';
      NO_DIR_CHECK='TRUE';
      ALLOW_CONNECT='TRUE';
    'GND_F14':
      PIN_NUMBER='(0,0,0,0,0,F14)';
      PINUSE='POWER';
      NO_LOAD_CHECK='Both';
      NO_IO_CHECK='Both';
      NO_ASSERT_CHECK='TRUE';
      NO_DIR_CHECK='TRUE';
      ALLOW_CONNECT='TRUE';
    'GND_F16':
      PIN_NUMBER='(0,0,0,0,0,F16)';
      PINUSE='POWER';
      NO_LOAD_CHECK='Both';
      NO_IO_CHECK='Both';
      NO_ASSERT_CHECK='TRUE';
      NO_DIR_CHECK='TRUE';
      ALLOW_CONNECT='TRUE';
    'GND_F17':
      PIN_NUMBER='(0,0,0,0,0,F17)';
      PINUSE='POWER';
      NO_LOAD_CHECK='Both';
      NO_IO_CHECK='Both';
      NO_ASSERT_CHECK='TRUE';
      NO_DIR_CHECK='TRUE';
      ALLOW_CONNECT='TRUE';
    'GND_F18':
      PIN_NUMBER='(0,0,0,0,0,F18)';
      PINUSE='POWER';
      NO_LOAD_CHECK='Both';
      NO_IO_CHECK='Both';
      NO_ASSERT_CHECK='TRUE';
      NO_DIR_CHECK='TRUE';
      ALLOW_CONNECT='TRUE';
    'GND_F21':
      PIN_NUMBER='(0,0,0,0,0,F21)';
      PINUSE='POWER';
      NO_LOAD_CHECK='Both';
      NO_IO_CHECK='Both';
      NO_ASSERT_CHECK='TRUE';
      NO_DIR_CHECK='TRUE';
      ALLOW_CONNECT='TRUE';
    'GND_G2':
      PIN_NUMBER='(0,0,0,0,0,G2)';
      PINUSE='POWER';
      NO_LOAD_CHECK='Both';
      NO_IO_CHECK='Both';
      NO_ASSERT_CHECK='TRUE';
      NO_DIR_CHECK='TRUE';
      ALLOW_CONNECT='TRUE';
    'GND_G25':
      PIN_NUMBER='(0,0,0,0,0,G25)';
      PINUSE='POWER';
      NO_LOAD_CHECK='Both';
      NO_IO_CHECK='Both';
      NO_ASSERT_CHECK='TRUE';
      NO_DIR_CHECK='TRUE';
      ALLOW_CONNECT='TRUE';
    'GND_H4':
      PIN_NUMBER='(0,0,0,0,0,H4)';
      PINUSE='POWER';
      NO_LOAD_CHECK='Both';
      NO_IO_CHECK='Both';
      NO_ASSERT_CHECK='TRUE';
      NO_DIR_CHECK='TRUE';
      ALLOW_CONNECT='TRUE';
    'GND_H9':
      PIN_NUMBER='(0,0,0,0,0,H9)';
      PINUSE='POWER';
      NO_LOAD_CHECK='Both';
      NO_IO_CHECK='Both';
      NO_ASSERT_CHECK='TRUE';
      NO_DIR_CHECK='TRUE';
      ALLOW_CONNECT='TRUE';
    'GND_H10':
      PIN_NUMBER='(0,0,0,0,0,H10)';
      PINUSE='POWER';
      NO_LOAD_CHECK='Both';
      NO_IO_CHECK='Both';
      NO_ASSERT_CHECK='TRUE';
      NO_DIR_CHECK='TRUE';
      ALLOW_CONNECT='TRUE';
    'GND_H11':
      PIN_NUMBER='(0,0,0,0,0,H11)';
      PINUSE='POWER';
      NO_LOAD_CHECK='Both';
      NO_IO_CHECK='Both';
      NO_ASSERT_CHECK='TRUE';
      NO_DIR_CHECK='TRUE';
      ALLOW_CONNECT='TRUE';
    'GND_H13':
      PIN_NUMBER='(0,0,0,0,0,H13)';
      PINUSE='POWER';
      NO_LOAD_CHECK='Both';
      NO_IO_CHECK='Both';
      NO_ASSERT_CHECK='TRUE';
      NO_DIR_CHECK='TRUE';
      ALLOW_CONNECT='TRUE';
    'GND_J2':
      PIN_NUMBER='(0,0,0,0,0,J2)';
      PINUSE='POWER';
      NO_LOAD_CHECK='Both';
      NO_IO_CHECK='Both';
      NO_ASSERT_CHECK='TRUE';
      NO_DIR_CHECK='TRUE';
      ALLOW_CONNECT='TRUE';
    'GND_J11':
      PIN_NUMBER='(0,0,0,0,0,J11)';
      PINUSE='POWER';
      NO_LOAD_CHECK='Both';
      NO_IO_CHECK='Both';
      NO_ASSERT_CHECK='TRUE';
      NO_DIR_CHECK='TRUE';
      ALLOW_CONNECT='TRUE';
    'GND_J13':
      PIN_NUMBER='(0,0,0,0,0,J13)';
      PINUSE='POWER';
      NO_LOAD_CHECK='Both';
      NO_IO_CHECK='Both';
      NO_ASSERT_CHECK='TRUE';
      NO_DIR_CHECK='TRUE';
      ALLOW_CONNECT='TRUE';
    'GND_J14':
      PIN_NUMBER='(0,0,0,0,0,J14)';
      PINUSE='POWER';
      NO_LOAD_CHECK='Both';
      NO_IO_CHECK='Both';
      NO_ASSERT_CHECK='TRUE';
      NO_DIR_CHECK='TRUE';
      ALLOW_CONNECT='TRUE';
    'GND_J15':
      PIN_NUMBER='(0,0,0,0,0,J15)';
      PINUSE='POWER';
      NO_LOAD_CHECK='Both';
      NO_IO_CHECK='Both';
      NO_ASSERT_CHECK='TRUE';
      NO_DIR_CHECK='TRUE';
      ALLOW_CONNECT='TRUE';
    'GND_J16':
      PIN_NUMBER='(0,0,0,0,0,J16)';
      PINUSE='POWER';
      NO_LOAD_CHECK='Both';
      NO_IO_CHECK='Both';
      NO_ASSERT_CHECK='TRUE';
      NO_DIR_CHECK='TRUE';
      ALLOW_CONNECT='TRUE';
    'GND_J17':
      PIN_NUMBER='(0,0,0,0,0,J17)';
      PINUSE='POWER';
      NO_LOAD_CHECK='Both';
      NO_IO_CHECK='Both';
      NO_ASSERT_CHECK='TRUE';
      NO_DIR_CHECK='TRUE';
      ALLOW_CONNECT='TRUE';
    'GND_J18':
      PIN_NUMBER='(0,0,0,0,0,J18)';
      PINUSE='POWER';
      NO_LOAD_CHECK='Both';
      NO_IO_CHECK='Both';
      NO_ASSERT_CHECK='TRUE';
      NO_DIR_CHECK='TRUE';
      ALLOW_CONNECT='TRUE';
    'GND_J19':
      PIN_NUMBER='(0,0,0,0,0,J19)';
      PINUSE='POWER';
      NO_LOAD_CHECK='Both';
      NO_IO_CHECK='Both';
      NO_ASSERT_CHECK='TRUE';
      NO_DIR_CHECK='TRUE';
      ALLOW_CONNECT='TRUE';
    'GND_K4':
      PIN_NUMBER='(0,0,0,0,0,K4)';
      PINUSE='POWER';
      NO_LOAD_CHECK='Both';
      NO_IO_CHECK='Both';
      NO_ASSERT_CHECK='TRUE';
      NO_DIR_CHECK='TRUE';
      ALLOW_CONNECT='TRUE';
    'GND_K8':
      PIN_NUMBER='(0,0,0,0,0,K8)';
      PINUSE='POWER';
      NO_LOAD_CHECK='Both';
      NO_IO_CHECK='Both';
      NO_ASSERT_CHECK='TRUE';
      NO_DIR_CHECK='TRUE';
      ALLOW_CONNECT='TRUE';
    'GND_K9':
      PIN_NUMBER='(0,0,0,0,0,K9)';
      PINUSE='POWER';
      NO_LOAD_CHECK='Both';
      NO_IO_CHECK='Both';
      NO_ASSERT_CHECK='TRUE';
      NO_DIR_CHECK='TRUE';
      ALLOW_CONNECT='TRUE';
    'GND_K13':
      PIN_NUMBER='(0,0,0,0,0,K13)';
      PINUSE='POWER';
      NO_LOAD_CHECK='Both';
      NO_IO_CHECK='Both';
      NO_ASSERT_CHECK='TRUE';
      NO_DIR_CHECK='TRUE';
      ALLOW_CONNECT='TRUE';
    'GND_K14':
      PIN_NUMBER='(0,0,0,0,0,K14)';
      PINUSE='POWER';
      NO_LOAD_CHECK='Both';
      NO_IO_CHECK='Both';
      NO_ASSERT_CHECK='TRUE';
      NO_DIR_CHECK='TRUE';
      ALLOW_CONNECT='TRUE';
    'GND_K15':
      PIN_NUMBER='(0,0,0,0,0,K15)';
      PINUSE='POWER';
      NO_LOAD_CHECK='Both';
      NO_IO_CHECK='Both';
      NO_ASSERT_CHECK='TRUE';
      NO_DIR_CHECK='TRUE';
      ALLOW_CONNECT='TRUE';
    'GND_K22':
      PIN_NUMBER='(0,0,0,0,0,K22)';
      PINUSE='POWER';
      NO_LOAD_CHECK='Both';
      NO_IO_CHECK='Both';
      NO_ASSERT_CHECK='TRUE';
      NO_DIR_CHECK='TRUE';
      ALLOW_CONNECT='TRUE';
    'GND_L2':
      PIN_NUMBER='(0,0,0,0,0,L2)';
      PINUSE='POWER';
      NO_LOAD_CHECK='Both';
      NO_IO_CHECK='Both';
      NO_ASSERT_CHECK='TRUE';
      NO_DIR_CHECK='TRUE';
      ALLOW_CONNECT='TRUE';
    'GND_L8':
      PIN_NUMBER='(0,0,0,0,0,L8)';
      PINUSE='POWER';
      NO_LOAD_CHECK='Both';
      NO_IO_CHECK='Both';
      NO_ASSERT_CHECK='TRUE';
      NO_DIR_CHECK='TRUE';
      ALLOW_CONNECT='TRUE';
    'GND_L11':
      PIN_NUMBER='(0,0,0,0,0,L11)';
      PINUSE='POWER';
      NO_LOAD_CHECK='Both';
      NO_IO_CHECK='Both';
      NO_ASSERT_CHECK='TRUE';
      NO_DIR_CHECK='TRUE';
      ALLOW_CONNECT='TRUE';
    'GND_L12':
      PIN_NUMBER='(0,0,0,0,0,L12)';
      PINUSE='POWER';
      NO_LOAD_CHECK='Both';
      NO_IO_CHECK='Both';
      NO_ASSERT_CHECK='TRUE';
      NO_DIR_CHECK='TRUE';
      ALLOW_CONNECT='TRUE';
    'GND_L15':
      PIN_NUMBER='(0,0,0,0,0,L15)';
      PINUSE='POWER';
      NO_LOAD_CHECK='Both';
      NO_IO_CHECK='Both';
      NO_ASSERT_CHECK='TRUE';
      NO_DIR_CHECK='TRUE';
      ALLOW_CONNECT='TRUE';
    'GND_L16':
      PIN_NUMBER='(0,0,0,0,0,L16)';
      PINUSE='POWER';
      NO_LOAD_CHECK='Both';
      NO_IO_CHECK='Both';
      NO_ASSERT_CHECK='TRUE';
      NO_DIR_CHECK='TRUE';
      ALLOW_CONNECT='TRUE';
    'GND_L17':
      PIN_NUMBER='(0,0,0,0,0,L17)';
      PINUSE='POWER';
      NO_LOAD_CHECK='Both';
      NO_IO_CHECK='Both';
      NO_ASSERT_CHECK='TRUE';
      NO_DIR_CHECK='TRUE';
      ALLOW_CONNECT='TRUE';
    'GND_R2':
      PIN_NUMBER='(0,0,0,0,0,R2)';
      PINUSE='POWER';
      NO_LOAD_CHECK='Both';
      NO_IO_CHECK='Both';
      NO_ASSERT_CHECK='TRUE';
      NO_DIR_CHECK='TRUE';
      ALLOW_CONNECT='TRUE';
    'GND_R8':
      PIN_NUMBER='(0,0,0,0,0,R8)';
      PINUSE='POWER';
      NO_LOAD_CHECK='Both';
      NO_IO_CHECK='Both';
      NO_ASSERT_CHECK='TRUE';
      NO_DIR_CHECK='TRUE';
      ALLOW_CONNECT='TRUE';
    'GND_R11':
      PIN_NUMBER='(0,0,0,0,0,R11)';
      PINUSE='POWER';
      NO_LOAD_CHECK='Both';
      NO_IO_CHECK='Both';
      NO_ASSERT_CHECK='TRUE';
      NO_DIR_CHECK='TRUE';
      ALLOW_CONNECT='TRUE';
    'GND_R15':
      PIN_NUMBER='(0,0,0,0,0,R15)';
      PINUSE='POWER';
      NO_LOAD_CHECK='Both';
      NO_IO_CHECK='Both';
      NO_ASSERT_CHECK='TRUE';
      NO_DIR_CHECK='TRUE';
      ALLOW_CONNECT='TRUE';
    'GND_R16':
      PIN_NUMBER='(0,0,0,0,0,R16)';
      PINUSE='POWER';
      NO_LOAD_CHECK='Both';
      NO_IO_CHECK='Both';
      NO_ASSERT_CHECK='TRUE';
      NO_DIR_CHECK='TRUE';
      ALLOW_CONNECT='TRUE';
    'GND_R17':
      PIN_NUMBER='(0,0,0,0,0,R17)';
      PINUSE='POWER';
      NO_LOAD_CHECK='Both';
      NO_IO_CHECK='Both';
      NO_ASSERT_CHECK='TRUE';
      NO_DIR_CHECK='TRUE';
      ALLOW_CONNECT='TRUE';
    'GND_R18':
      PIN_NUMBER='(0,0,0,0,0,R18)';
      PINUSE='POWER';
      NO_LOAD_CHECK='Both';
      NO_IO_CHECK='Both';
      NO_ASSERT_CHECK='TRUE';
      NO_DIR_CHECK='TRUE';
      ALLOW_CONNECT='TRUE';
    'GND_R19':
      PIN_NUMBER='(0,0,0,0,0,R19)';
      PINUSE='POWER';
      NO_LOAD_CHECK='Both';
      NO_IO_CHECK='Both';
      NO_ASSERT_CHECK='TRUE';
      NO_DIR_CHECK='TRUE';
      ALLOW_CONNECT='TRUE';
    'GND_R25':
      PIN_NUMBER='(0,0,0,0,0,R25)';
      PINUSE='POWER';
      NO_LOAD_CHECK='Both';
      NO_IO_CHECK='Both';
      NO_ASSERT_CHECK='TRUE';
      NO_DIR_CHECK='TRUE';
      ALLOW_CONNECT='TRUE';
    'GND_T4':
      PIN_NUMBER='(0,0,0,0,0,T4)';
      PINUSE='POWER';
      NO_LOAD_CHECK='Both';
      NO_IO_CHECK='Both';
      NO_ASSERT_CHECK='TRUE';
      NO_DIR_CHECK='TRUE';
      ALLOW_CONNECT='TRUE';
    'GND_T11':
      PIN_NUMBER='(0,0,0,0,0,T11)';
      PINUSE='POWER';
      NO_LOAD_CHECK='Both';
      NO_IO_CHECK='Both';
      NO_ASSERT_CHECK='TRUE';
      NO_DIR_CHECK='TRUE';
      ALLOW_CONNECT='TRUE';
    'GND_T12':
      PIN_NUMBER='(0,0,0,0,0,T12)';
      PINUSE='POWER';
      NO_LOAD_CHECK='Both';
      NO_IO_CHECK='Both';
      NO_ASSERT_CHECK='TRUE';
      NO_DIR_CHECK='TRUE';
      ALLOW_CONNECT='TRUE';
    'GND_T15':
      PIN_NUMBER='(0,0,0,0,0,T15)';
      PINUSE='POWER';
      NO_LOAD_CHECK='Both';
      NO_IO_CHECK='Both';
      NO_ASSERT_CHECK='TRUE';
      NO_DIR_CHECK='TRUE';
      ALLOW_CONNECT='TRUE';
    'GND_T16':
      PIN_NUMBER='(0,0,0,0,0,T16)';
      PINUSE='POWER';
      NO_LOAD_CHECK='Both';
      NO_IO_CHECK='Both';
      NO_ASSERT_CHECK='TRUE';
      NO_DIR_CHECK='TRUE';
      ALLOW_CONNECT='TRUE';
    'GND_T17':
      PIN_NUMBER='(0,0,0,0,0,T17)';
      PINUSE='POWER';
      NO_LOAD_CHECK='Both';
      NO_IO_CHECK='Both';
      NO_ASSERT_CHECK='TRUE';
      NO_DIR_CHECK='TRUE';
      ALLOW_CONNECT='TRUE';
    'GND_T18':
      PIN_NUMBER='(0,0,0,0,0,T18)';
      PINUSE='POWER';
      NO_LOAD_CHECK='Both';
      NO_IO_CHECK='Both';
      NO_ASSERT_CHECK='TRUE';
      NO_DIR_CHECK='TRUE';
      ALLOW_CONNECT='TRUE';
    'GND_T19':
      PIN_NUMBER='(0,0,0,0,0,T19)';
      PINUSE='POWER';
      NO_LOAD_CHECK='Both';
      NO_IO_CHECK='Both';
      NO_ASSERT_CHECK='TRUE';
      NO_DIR_CHECK='TRUE';
      ALLOW_CONNECT='TRUE';
    'GND_U2':
      PIN_NUMBER='(0,0,0,0,0,U2)';
      PINUSE='POWER';
      NO_LOAD_CHECK='Both';
      NO_IO_CHECK='Both';
      NO_ASSERT_CHECK='TRUE';
      NO_DIR_CHECK='TRUE';
      ALLOW_CONNECT='TRUE';
    'GND_U8':
      PIN_NUMBER='(0,0,0,0,0,U8)';
      PINUSE='POWER';
      NO_LOAD_CHECK='Both';
      NO_IO_CHECK='Both';
      NO_ASSERT_CHECK='TRUE';
      NO_DIR_CHECK='TRUE';
      ALLOW_CONNECT='TRUE';
    'GND_U9':
      PIN_NUMBER='(0,0,0,0,0,U9)';
      PINUSE='POWER';
      NO_LOAD_CHECK='Both';
      NO_IO_CHECK='Both';
      NO_ASSERT_CHECK='TRUE';
      NO_DIR_CHECK='TRUE';
      ALLOW_CONNECT='TRUE';
    'GND_U10':
      PIN_NUMBER='(0,0,0,0,0,U10)';
      PINUSE='POWER';
      NO_LOAD_CHECK='Both';
      NO_IO_CHECK='Both';
      NO_ASSERT_CHECK='TRUE';
      NO_DIR_CHECK='TRUE';
      ALLOW_CONNECT='TRUE';
    'GND_U11':
      PIN_NUMBER='(0,0,0,0,0,U11)';
      PINUSE='POWER';
      NO_LOAD_CHECK='Both';
      NO_IO_CHECK='Both';
      NO_ASSERT_CHECK='TRUE';
      NO_DIR_CHECK='TRUE';
      ALLOW_CONNECT='TRUE';
    'GND_U12':
      PIN_NUMBER='(0,0,0,0,0,U12)';
      PINUSE='POWER';
      NO_LOAD_CHECK='Both';
      NO_IO_CHECK='Both';
      NO_ASSERT_CHECK='TRUE';
      NO_DIR_CHECK='TRUE';
      ALLOW_CONNECT='TRUE';
    'GND_U14':
      PIN_NUMBER='(0,0,0,0,0,U14)';
      PINUSE='POWER';
      NO_LOAD_CHECK='Both';
      NO_IO_CHECK='Both';
      NO_ASSERT_CHECK='TRUE';
      NO_DIR_CHECK='TRUE';
      ALLOW_CONNECT='TRUE';
    'GND_U19':
      PIN_NUMBER='(0,0,0,0,0,U19)';
      PINUSE='POWER';
      NO_LOAD_CHECK='Both';
      NO_IO_CHECK='Both';
      NO_ASSERT_CHECK='TRUE';
      NO_DIR_CHECK='TRUE';
      ALLOW_CONNECT='TRUE';
    'GND_U22':
      PIN_NUMBER='(0,0,0,0,0,U22)';
      PINUSE='POWER';
      NO_LOAD_CHECK='Both';
      NO_IO_CHECK='Both';
      NO_ASSERT_CHECK='TRUE';
      NO_DIR_CHECK='TRUE';
      ALLOW_CONNECT='TRUE';
    'GND_V5':
      PIN_NUMBER='(0,0,0,0,0,V5)';
      PINUSE='POWER';
      NO_LOAD_CHECK='Both';
      NO_IO_CHECK='Both';
      NO_ASSERT_CHECK='TRUE';
      NO_DIR_CHECK='TRUE';
      ALLOW_CONNECT='TRUE';
    'GND_V11':
      PIN_NUMBER='(0,0,0,0,0,V11)';
      PINUSE='POWER';
      NO_LOAD_CHECK='Both';
      NO_IO_CHECK='Both';
      NO_ASSERT_CHECK='TRUE';
      NO_DIR_CHECK='TRUE';
      ALLOW_CONNECT='TRUE';
    'GND_V12':
      PIN_NUMBER='(0,0,0,0,0,V12)';
      PINUSE='POWER';
      NO_LOAD_CHECK='Both';
      NO_IO_CHECK='Both';
      NO_ASSERT_CHECK='TRUE';
      NO_DIR_CHECK='TRUE';
      ALLOW_CONNECT='TRUE';
    'GND_V14':
      PIN_NUMBER='(0,0,0,0,0,V14)';
      PINUSE='POWER';
      NO_LOAD_CHECK='Both';
      NO_IO_CHECK='Both';
      NO_ASSERT_CHECK='TRUE';
      NO_DIR_CHECK='TRUE';
      ALLOW_CONNECT='TRUE';
    'GND_V15':
      PIN_NUMBER='(0,0,0,0,0,V15)';
      PINUSE='POWER';
      NO_LOAD_CHECK='Both';
      NO_IO_CHECK='Both';
      NO_ASSERT_CHECK='TRUE';
      NO_DIR_CHECK='TRUE';
      ALLOW_CONNECT='TRUE';
    'GND_V16':
      PIN_NUMBER='(0,0,0,0,0,V16)';
      PINUSE='POWER';
      NO_LOAD_CHECK='Both';
      NO_IO_CHECK='Both';
      NO_ASSERT_CHECK='TRUE';
      NO_DIR_CHECK='TRUE';
      ALLOW_CONNECT='TRUE';
    'GND_V17':
      PIN_NUMBER='(0,0,0,0,0,V17)';
      PINUSE='POWER';
      NO_LOAD_CHECK='Both';
      NO_IO_CHECK='Both';
      NO_ASSERT_CHECK='TRUE';
      NO_DIR_CHECK='TRUE';
      ALLOW_CONNECT='TRUE';
    'GND_V18':
      PIN_NUMBER='(0,0,0,0,0,V18)';
      PINUSE='POWER';
      NO_LOAD_CHECK='Both';
      NO_IO_CHECK='Both';
      NO_ASSERT_CHECK='TRUE';
      NO_DIR_CHECK='TRUE';
      ALLOW_CONNECT='TRUE';
    'GND_V19':
      PIN_NUMBER='(0,0,0,0,0,V19)';
      PINUSE='POWER';
      NO_LOAD_CHECK='Both';
      NO_IO_CHECK='Both';
      NO_ASSERT_CHECK='TRUE';
      NO_DIR_CHECK='TRUE';
      ALLOW_CONNECT='TRUE';
    'GND_W5':
      PIN_NUMBER='(0,0,0,0,0,W5)';
      PINUSE='POWER';
      NO_LOAD_CHECK='Both';
      NO_IO_CHECK='Both';
      NO_ASSERT_CHECK='TRUE';
      NO_DIR_CHECK='TRUE';
      ALLOW_CONNECT='TRUE';
    'GND_W6':
      PIN_NUMBER='(0,0,0,0,0,W6)';
      PINUSE='POWER';
      NO_LOAD_CHECK='Both';
      NO_IO_CHECK='Both';
      NO_ASSERT_CHECK='TRUE';
      NO_DIR_CHECK='TRUE';
      ALLOW_CONNECT='TRUE';
    'GND_W8':
      PIN_NUMBER='(0,0,0,0,0,W8)';
      PINUSE='POWER';
      NO_LOAD_CHECK='Both';
      NO_IO_CHECK='Both';
      NO_ASSERT_CHECK='TRUE';
      NO_DIR_CHECK='TRUE';
      ALLOW_CONNECT='TRUE';
    'GND_W9':
      PIN_NUMBER='(0,0,0,0,0,W9)';
      PINUSE='POWER';
      NO_LOAD_CHECK='Both';
      NO_IO_CHECK='Both';
      NO_ASSERT_CHECK='TRUE';
      NO_DIR_CHECK='TRUE';
      ALLOW_CONNECT='TRUE';
    'GND_W10':
      PIN_NUMBER='(0,0,0,0,0,W10)';
      PINUSE='POWER';
      NO_LOAD_CHECK='Both';
      NO_IO_CHECK='Both';
      NO_ASSERT_CHECK='TRUE';
      NO_DIR_CHECK='TRUE';
      ALLOW_CONNECT='TRUE';
    'GND_W11':
      PIN_NUMBER='(0,0,0,0,0,W11)';
      PINUSE='POWER';
      NO_LOAD_CHECK='Both';
      NO_IO_CHECK='Both';
      NO_ASSERT_CHECK='TRUE';
      NO_DIR_CHECK='TRUE';
      ALLOW_CONNECT='TRUE';
    'GND_W12':
      PIN_NUMBER='(0,0,0,0,0,W12)';
      PINUSE='POWER';
      NO_LOAD_CHECK='Both';
      NO_IO_CHECK='Both';
      NO_ASSERT_CHECK='TRUE';
      NO_DIR_CHECK='TRUE';
      ALLOW_CONNECT='TRUE';
    'GND_L18':
      PIN_NUMBER='(0,0,0,0,0,L18)';
      PINUSE='POWER';
      NO_LOAD_CHECK='Both';
      NO_IO_CHECK='Both';
      NO_ASSERT_CHECK='TRUE';
      NO_DIR_CHECK='TRUE';
      ALLOW_CONNECT='TRUE';
    'GND_L19':
      PIN_NUMBER='(0,0,0,0,0,L19)';
      PINUSE='POWER';
      NO_LOAD_CHECK='Both';
      NO_IO_CHECK='Both';
      NO_ASSERT_CHECK='TRUE';
      NO_DIR_CHECK='TRUE';
      ALLOW_CONNECT='TRUE';
    'GND_L25':
      PIN_NUMBER='(0,0,0,0,0,L25)';
      PINUSE='POWER';
      NO_LOAD_CHECK='Both';
      NO_IO_CHECK='Both';
      NO_ASSERT_CHECK='TRUE';
      NO_DIR_CHECK='TRUE';
      ALLOW_CONNECT='TRUE';
    'GND_M4':
      PIN_NUMBER='(0,0,0,0,0,M4)';
      PINUSE='POWER';
      NO_LOAD_CHECK='Both';
      NO_IO_CHECK='Both';
      NO_ASSERT_CHECK='TRUE';
      NO_DIR_CHECK='TRUE';
      ALLOW_CONNECT='TRUE';
    'GND_M9':
      PIN_NUMBER='(0,0,0,0,0,M9)';
      PINUSE='POWER';
      NO_LOAD_CHECK='Both';
      NO_IO_CHECK='Both';
      NO_ASSERT_CHECK='TRUE';
      NO_DIR_CHECK='TRUE';
      ALLOW_CONNECT='TRUE';
    'GND_M10':
      PIN_NUMBER='(0,0,0,0,0,M10)';
      PINUSE='POWER';
      NO_LOAD_CHECK='Both';
      NO_IO_CHECK='Both';
      NO_ASSERT_CHECK='TRUE';
      NO_DIR_CHECK='TRUE';
      ALLOW_CONNECT='TRUE';
    'GND_M12':
      PIN_NUMBER='(0,0,0,0,0,M12)';
      PINUSE='POWER';
      NO_LOAD_CHECK='Both';
      NO_IO_CHECK='Both';
      NO_ASSERT_CHECK='TRUE';
      NO_DIR_CHECK='TRUE';
      ALLOW_CONNECT='TRUE';
    'GND_M15':
      PIN_NUMBER='(0,0,0,0,0,M15)';
      PINUSE='POWER';
      NO_LOAD_CHECK='Both';
      NO_IO_CHECK='Both';
      NO_ASSERT_CHECK='TRUE';
      NO_DIR_CHECK='TRUE';
      ALLOW_CONNECT='TRUE';
    'GND_M16':
      PIN_NUMBER='(0,0,0,0,0,M16)';
      PINUSE='POWER';
      NO_LOAD_CHECK='Both';
      NO_IO_CHECK='Both';
      NO_ASSERT_CHECK='TRUE';
      NO_DIR_CHECK='TRUE';
      ALLOW_CONNECT='TRUE';
    'GND_M17':
      PIN_NUMBER='(0,0,0,0,0,M17)';
      PINUSE='POWER';
      NO_LOAD_CHECK='Both';
      NO_IO_CHECK='Both';
      NO_ASSERT_CHECK='TRUE';
      NO_DIR_CHECK='TRUE';
      ALLOW_CONNECT='TRUE';
    'GND_W22':
      PIN_NUMBER='(0,0,0,0,0,W22)';
      PINUSE='POWER';
      NO_LOAD_CHECK='Both';
      NO_IO_CHECK='Both';
      NO_ASSERT_CHECK='TRUE';
      NO_DIR_CHECK='TRUE';
      ALLOW_CONNECT='TRUE';
    'GND_W25':
      PIN_NUMBER='(0,0,0,0,0,W25)';
      PINUSE='POWER';
      NO_LOAD_CHECK='Both';
      NO_IO_CHECK='Both';
      NO_ASSERT_CHECK='TRUE';
      NO_DIR_CHECK='TRUE';
      ALLOW_CONNECT='TRUE';
    'GND_Y6':
      PIN_NUMBER='(0,0,0,0,0,Y6)';
      PINUSE='POWER';
      NO_LOAD_CHECK='Both';
      NO_IO_CHECK='Both';
      NO_ASSERT_CHECK='TRUE';
      NO_DIR_CHECK='TRUE';
      ALLOW_CONNECT='TRUE';
    'GND_Y22':
      PIN_NUMBER='(0,0,0,0,0,Y22)';
      PINUSE='POWER';
      NO_LOAD_CHECK='Both';
      NO_IO_CHECK='Both';
      NO_ASSERT_CHECK='TRUE';
      NO_DIR_CHECK='TRUE';
      ALLOW_CONNECT='TRUE';
    'GND_AA1':
      PIN_NUMBER='(0,0,0,0,0,AA1)';
      PINUSE='POWER';
      NO_LOAD_CHECK='Both';
      NO_IO_CHECK='Both';
      NO_ASSERT_CHECK='TRUE';
      NO_DIR_CHECK='TRUE';
      ALLOW_CONNECT='TRUE';
    'GND_AA3':
      PIN_NUMBER='(0,0,0,0,0,AA3)';
      PINUSE='POWER';
      NO_LOAD_CHECK='Both';
      NO_IO_CHECK='Both';
      NO_ASSERT_CHECK='TRUE';
      NO_DIR_CHECK='TRUE';
      ALLOW_CONNECT='TRUE';
    'GND_AA8':
      PIN_NUMBER='(0,0,0,0,0,AA8)';
      PINUSE='POWER';
      NO_LOAD_CHECK='Both';
      NO_IO_CHECK='Both';
      NO_ASSERT_CHECK='TRUE';
      NO_DIR_CHECK='TRUE';
      ALLOW_CONNECT='TRUE';
    'GND_AA7':
      PIN_NUMBER='(0,0,0,0,0,AA7)';
      PINUSE='POWER';
      NO_LOAD_CHECK='Both';
      NO_IO_CHECK='Both';
      NO_ASSERT_CHECK='TRUE';
      NO_DIR_CHECK='TRUE';
      ALLOW_CONNECT='TRUE';
    'GND_AA6':
      PIN_NUMBER='(0,0,0,0,0,AA6)';
      PINUSE='POWER';
      NO_LOAD_CHECK='Both';
      NO_IO_CHECK='Both';
      NO_ASSERT_CHECK='TRUE';
      NO_DIR_CHECK='TRUE';
      ALLOW_CONNECT='TRUE';
    'GND_M18':
      PIN_NUMBER='(0,0,0,0,0,M18)';
      PINUSE='POWER';
      NO_LOAD_CHECK='Both';
      NO_IO_CHECK='Both';
      NO_ASSERT_CHECK='TRUE';
      NO_DIR_CHECK='TRUE';
      ALLOW_CONNECT='TRUE';
    'GND_M19':
      PIN_NUMBER='(0,0,0,0,0,M19)';
      PINUSE='POWER';
      NO_LOAD_CHECK='Both';
      NO_IO_CHECK='Both';
      NO_ASSERT_CHECK='TRUE';
      NO_DIR_CHECK='TRUE';
      ALLOW_CONNECT='TRUE';
    'GND_N2':
      PIN_NUMBER='(0,0,0,0,0,N2)';
      PINUSE='POWER';
      NO_LOAD_CHECK='Both';
      NO_IO_CHECK='Both';
      NO_ASSERT_CHECK='TRUE';
      NO_DIR_CHECK='TRUE';
      ALLOW_CONNECT='TRUE';
    'GND_N6':
      PIN_NUMBER='(0,0,0,0,0,N6)';
      PINUSE='POWER';
      NO_LOAD_CHECK='Both';
      NO_IO_CHECK='Both';
      NO_ASSERT_CHECK='TRUE';
      NO_DIR_CHECK='TRUE';
      ALLOW_CONNECT='TRUE';
    'GND_N9':
      PIN_NUMBER='(0,0,0,0,0,N9)';
      PINUSE='POWER';
      NO_LOAD_CHECK='Both';
      NO_IO_CHECK='Both';
      NO_ASSERT_CHECK='TRUE';
      NO_DIR_CHECK='TRUE';
      ALLOW_CONNECT='TRUE';
    'GND_N10':
      PIN_NUMBER='(0,0,0,0,0,N10)';
      PINUSE='POWER';
      NO_LOAD_CHECK='Both';
      NO_IO_CHECK='Both';
      NO_ASSERT_CHECK='TRUE';
      NO_DIR_CHECK='TRUE';
      ALLOW_CONNECT='TRUE';
    'GND_N15':
      PIN_NUMBER='(0,0,0,0,0,N15)';
      PINUSE='POWER';
      NO_LOAD_CHECK='Both';
      NO_IO_CHECK='Both';
      NO_ASSERT_CHECK='TRUE';
      NO_DIR_CHECK='TRUE';
      ALLOW_CONNECT='TRUE';
    'GND_N16':
      PIN_NUMBER='(0,0,0,0,0,N16)';
      PINUSE='POWER';
      NO_LOAD_CHECK='Both';
      NO_IO_CHECK='Both';
      NO_ASSERT_CHECK='TRUE';
      NO_DIR_CHECK='TRUE';
      ALLOW_CONNECT='TRUE';
    'GND_N17':
      PIN_NUMBER='(0,0,0,0,0,N17)';
      PINUSE='POWER';
      NO_LOAD_CHECK='Both';
      NO_IO_CHECK='Both';
      NO_ASSERT_CHECK='TRUE';
      NO_DIR_CHECK='TRUE';
      ALLOW_CONNECT='TRUE';
    'GND_N18':
      PIN_NUMBER='(0,0,0,0,0,N18)';
      PINUSE='POWER';
      NO_LOAD_CHECK='Both';
      NO_IO_CHECK='Both';
      NO_ASSERT_CHECK='TRUE';
      NO_DIR_CHECK='TRUE';
      ALLOW_CONNECT='TRUE';
    'GND_N19':
      PIN_NUMBER='(0,0,0,0,0,N19)';
      PINUSE='POWER';
      NO_LOAD_CHECK='Both';
      NO_IO_CHECK='Both';
      NO_ASSERT_CHECK='TRUE';
      NO_DIR_CHECK='TRUE';
      ALLOW_CONNECT='TRUE';
    'GND_AA10':
      PIN_NUMBER='(0,0,0,0,0,AA10)';
      PINUSE='POWER';
      NO_LOAD_CHECK='Both';
      NO_IO_CHECK='Both';
      NO_ASSERT_CHECK='TRUE';
      NO_DIR_CHECK='TRUE';
      ALLOW_CONNECT='TRUE';
    'GND_AA14':
      PIN_NUMBER='(0,0,0,0,0,AA14)';
      PINUSE='POWER';
      NO_LOAD_CHECK='Both';
      NO_IO_CHECK='Both';
      NO_ASSERT_CHECK='TRUE';
      NO_DIR_CHECK='TRUE';
      ALLOW_CONNECT='TRUE';
    'GND_AA15':
      PIN_NUMBER='(0,0,0,0,0,AA15)';
      PINUSE='POWER';
      NO_LOAD_CHECK='Both';
      NO_IO_CHECK='Both';
      NO_ASSERT_CHECK='TRUE';
      NO_DIR_CHECK='TRUE';
      ALLOW_CONNECT='TRUE';
    'GND_AA19':
      PIN_NUMBER='(0,0,0,0,0,AA19)';
      PINUSE='POWER';
      NO_LOAD_CHECK='Both';
      NO_IO_CHECK='Both';
      NO_ASSERT_CHECK='TRUE';
      NO_DIR_CHECK='TRUE';
      ALLOW_CONNECT='TRUE';
    'GND_AA22':
      PIN_NUMBER='(0,0,0,0,0,AA22)';
      PINUSE='POWER';
      NO_LOAD_CHECK='Both';
      NO_IO_CHECK='Both';
      NO_ASSERT_CHECK='TRUE';
      NO_DIR_CHECK='TRUE';
      ALLOW_CONNECT='TRUE';
    'GND_AC2':
      PIN_NUMBER='(0,0,0,0,0,AC2)';
      PINUSE='POWER';
      NO_LOAD_CHECK='Both';
      NO_IO_CHECK='Both';
      NO_ASSERT_CHECK='TRUE';
      NO_DIR_CHECK='TRUE';
      ALLOW_CONNECT='TRUE';
    'GND_AC6':
      PIN_NUMBER='(0,0,0,0,0,AC6)';
      PINUSE='POWER';
      NO_LOAD_CHECK='Both';
      NO_IO_CHECK='Both';
      NO_ASSERT_CHECK='TRUE';
      NO_DIR_CHECK='TRUE';
      ALLOW_CONNECT='TRUE';
    'GND_AC25':
      PIN_NUMBER='(0,0,0,0,0,AC25)';
      PINUSE='POWER';
      NO_LOAD_CHECK='Both';
      NO_IO_CHECK='Both';
      NO_ASSERT_CHECK='TRUE';
      NO_DIR_CHECK='TRUE';
      ALLOW_CONNECT='TRUE';
    'GND_AD1':
      PIN_NUMBER='(0,0,0,0,0,AD1)';
      PINUSE='POWER';
      NO_LOAD_CHECK='Both';
      NO_IO_CHECK='Both';
      NO_ASSERT_CHECK='TRUE';
      NO_DIR_CHECK='TRUE';
      ALLOW_CONNECT='TRUE';
    'GND_AD4':
      PIN_NUMBER='(0,0,0,0,0,AD4)';
      PINUSE='POWER';
      NO_LOAD_CHECK='Both';
      NO_IO_CHECK='Both';
      NO_ASSERT_CHECK='TRUE';
      NO_DIR_CHECK='TRUE';
      ALLOW_CONNECT='TRUE';
    'GND_AE3':
      PIN_NUMBER='(0,0,0,0,0,AE3)';
      PINUSE='POWER';
      NO_LOAD_CHECK='Both';
      NO_IO_CHECK='Both';
      NO_ASSERT_CHECK='TRUE';
      NO_DIR_CHECK='TRUE';
      ALLOW_CONNECT='TRUE';
    'GND_AE6':
      PIN_NUMBER='(0,0,0,0,0,AE6)';
      PINUSE='POWER';
      NO_LOAD_CHECK='Both';
      NO_IO_CHECK='Both';
      NO_ASSERT_CHECK='TRUE';
      NO_DIR_CHECK='TRUE';
      ALLOW_CONNECT='TRUE';
    'GND_AE9':
      PIN_NUMBER='(0,0,0,0,0,AE9)';
      PINUSE='POWER';
      NO_LOAD_CHECK='Both';
      NO_IO_CHECK='Both';
      NO_ASSERT_CHECK='TRUE';
      NO_DIR_CHECK='TRUE';
      ALLOW_CONNECT='TRUE';
    'GND_AE13':
      PIN_NUMBER='(0,0,0,0,0,AE13)';
      PINUSE='POWER';
      NO_LOAD_CHECK='Both';
      NO_IO_CHECK='Both';
      NO_ASSERT_CHECK='TRUE';
      NO_DIR_CHECK='TRUE';
      ALLOW_CONNECT='TRUE';
    'GND_AE17':
      PIN_NUMBER='(0,0,0,0,0,AE17)';
      PINUSE='POWER';
      NO_LOAD_CHECK='Both';
      NO_IO_CHECK='Both';
      NO_ASSERT_CHECK='TRUE';
      NO_DIR_CHECK='TRUE';
      ALLOW_CONNECT='TRUE';
    'GND_AE20':
      PIN_NUMBER='(0,0,0,0,0,AE20)';
      PINUSE='POWER';
      NO_LOAD_CHECK='Both';
      NO_IO_CHECK='Both';
      NO_ASSERT_CHECK='TRUE';
      NO_DIR_CHECK='TRUE';
      ALLOW_CONNECT='TRUE';
    'GND_AE23':
      PIN_NUMBER='(0,0,0,0,0,AE23)';
      PINUSE='POWER';
      NO_LOAD_CHECK='Both';
      NO_IO_CHECK='Both';
      NO_ASSERT_CHECK='TRUE';
      NO_DIR_CHECK='TRUE';
      ALLOW_CONNECT='TRUE';
    'GND_AF1':
      PIN_NUMBER='(0,0,0,0,0,AF1)';
      PINUSE='POWER';
      NO_LOAD_CHECK='Both';
      NO_IO_CHECK='Both';
      NO_ASSERT_CHECK='TRUE';
      NO_DIR_CHECK='TRUE';
      ALLOW_CONNECT='TRUE';
    'GND_AF4':
      PIN_NUMBER='(0,0,0,0,0,AF4)';
      PINUSE='POWER';
      NO_LOAD_CHECK='Both';
      NO_IO_CHECK='Both';
      NO_ASSERT_CHECK='TRUE';
      NO_DIR_CHECK='TRUE';
      ALLOW_CONNECT='TRUE';
    'GND_AF26':
      PIN_NUMBER='(0,0,0,0,0,AF26)';
      PINUSE='POWER';
      NO_LOAD_CHECK='Both';
      NO_IO_CHECK='Both';
      NO_ASSERT_CHECK='TRUE';
      NO_DIR_CHECK='TRUE';
      ALLOW_CONNECT='TRUE';
    'GND_P4':
      PIN_NUMBER='(0,0,0,0,0,P4)';
      PINUSE='POWER';
      NO_LOAD_CHECK='Both';
      NO_IO_CHECK='Both';
      NO_ASSERT_CHECK='TRUE';
      NO_DIR_CHECK='TRUE';
      ALLOW_CONNECT='TRUE';
    'GND_P9':
      PIN_NUMBER='(0,0,0,0,0,P9)';
      PINUSE='POWER';
      NO_LOAD_CHECK='Both';
      NO_IO_CHECK='Both';
      NO_ASSERT_CHECK='TRUE';
      NO_DIR_CHECK='TRUE';
      ALLOW_CONNECT='TRUE';
    'GND_P10':
      PIN_NUMBER='(0,0,0,0,0,P10)';
      PINUSE='POWER';
      NO_LOAD_CHECK='Both';
      NO_IO_CHECK='Both';
      NO_ASSERT_CHECK='TRUE';
      NO_DIR_CHECK='TRUE';
      ALLOW_CONNECT='TRUE';
    'GND_P15':
      PIN_NUMBER='(0,0,0,0,0,P15)';
      PINUSE='POWER';
      NO_LOAD_CHECK='Both';
      NO_IO_CHECK='Both';
      NO_ASSERT_CHECK='TRUE';
      NO_DIR_CHECK='TRUE';
      ALLOW_CONNECT='TRUE';
    'GND_P16':
      PIN_NUMBER='(0,0,0,0,0,P16)';
      PINUSE='POWER';
      NO_LOAD_CHECK='Both';
      NO_IO_CHECK='Both';
      NO_ASSERT_CHECK='TRUE';
      NO_DIR_CHECK='TRUE';
      ALLOW_CONNECT='TRUE';
    'GND_P17':
      PIN_NUMBER='(0,0,0,0,0,P17)';
      PINUSE='POWER';
      NO_LOAD_CHECK='Both';
      NO_IO_CHECK='Both';
      NO_ASSERT_CHECK='TRUE';
      NO_DIR_CHECK='TRUE';
      ALLOW_CONNECT='TRUE';
    'GND_P18':
      PIN_NUMBER='(0,0,0,0,0,P18)';
      PINUSE='POWER';
      NO_LOAD_CHECK='Both';
      NO_IO_CHECK='Both';
      NO_ASSERT_CHECK='TRUE';
      NO_DIR_CHECK='TRUE';
      ALLOW_CONNECT='TRUE';
    'GND_P19':
      PIN_NUMBER='(0,0,0,0,0,P19)';
      PINUSE='POWER';
      NO_LOAD_CHECK='Both';
      NO_IO_CHECK='Both';
      NO_ASSERT_CHECK='TRUE';
      NO_DIR_CHECK='TRUE';
      ALLOW_CONNECT='TRUE';
    'GND_AA20':
      PIN_NUMBER='(0,0,0,0,0,AA20)';
      PINUSE='POWER';
      NO_LOAD_CHECK='Both';
      NO_IO_CHECK='Both';
      NO_ASSERT_CHECK='TRUE';
      NO_DIR_CHECK='TRUE';
      ALLOW_CONNECT='TRUE';
    'GND_U23':
      PIN_NUMBER='(0,0,0,0,0,U23)';
      PINUSE='POWER';
      NO_LOAD_CHECK='Both';
      NO_IO_CHECK='Both';
      NO_ASSERT_CHECK='TRUE';
      NO_DIR_CHECK='TRUE';
      ALLOW_CONNECT='TRUE';
  end_pin;
  body
    PART_NAME='AST2600A3GP';
    BODY_NAME='AST2600A3GP';
    PHYS_DES_PREFIX='U';
    CLASS='IC';
  end_body;
end_primitive;

END.
